G04 ================== begin FILE IDENTIFICATION RECORD ==================*
G04 Layout Name:  14545-sa.brd*
G04 Film Name:    L4VCC*
G04 File Format:  Gerber RS274X*
G04 File Origin:  Cadence Allegro 16.5-S056*
G04 Origin Date:  Fri Aug 01 17:58:46 2014*
G04 *
G04 Layer:  VIA CLASS/L4VCC*
G04 Layer:  PIN/L4VCC*
G04 Layer:  PACKAGE GEOMETRY/PWRVCC*
G04 Layer:  ETCH/L4VCC*
G04 Layer:  DRAWING FORMAT/LAYER_PCB_STORY*
G04 Layer:  DRAWING FORMAT/LAYER_L4VCC*
G04 *
G04 Offset:    (0.00 0.00)*
G04 Mirror:    No*
G04 Mode:      Negative*
G04 Rotation:  0*
G04 FullContactRelief:  No*
G04 UndefLineWidth:     6.00*
G04 ================== end FILE IDENTIFICATION RECORD ====================*
%FSLAX35Y35*MOIN*%
%IR0*IPPOS*OFA0.00000B0.00000*MIA0B0*SFA1.00000B1.00000*%
%ADD15O,.115X.072*%
%ADD13C,.032*%
%ADD11C,.036*%
%AMMACRO20*
4,1,15,.00398,.00044,
.003999,.000208,
.004004,-.000025,
.003996,-.000258,
.00398,-.00044,
.00483,-.00129,
.004897,-.001007,
.004947,-.000721,
.004981,-.000432,
.004997,-.000141,
.004997,.000149,
.00498,.00044,
.004946,.000729,
.004895,.001015,
.00483,.00129,
.00398,.00044,
90.*
4,1,15,.00044,-.00398,
.000208,-.003999,
-.000025,-.004004,
-.000258,-.003996,
-.00044,-.00398,
-.00129,-.00483,
-.001007,-.004897,
-.000721,-.004947,
-.000432,-.004981,
-.000141,-.004997,
.000149,-.004997,
.00044,-.00498,
.000729,-.004946,
.001015,-.004895,
.00129,-.00483,
.00044,-.00398,
90.*
4,1,15,-.00398,-.00044,
-.003999,-.000208,
-.004004,.000025,
-.003996,.000258,
-.00398,.00044,
-.00483,.00129,
-.004897,.001007,
-.004947,.000721,
-.004981,.000432,
-.004997,.000141,
-.004997,-.000149,
-.00498,-.00044,
-.004946,-.000729,
-.004895,-.001015,
-.00483,-.00129,
-.00398,-.00044,
90.*
4,1,15,-.00044,.00398,
-.000208,.003999,
.000025,.004004,
.000258,.003996,
.00044,.00398,
.00129,.00483,
.001007,.004897,
.000721,.004947,
.000432,.004981,
.000141,.004997,
-.000149,.004997,
-.00044,.00498,
-.000729,.004946,
-.001015,.004895,
-.00129,.00483,
-.00044,.00398,
90.*
%
%ADD20MACRO20*%
%AMMACRO17*
4,1,15,.00398,.00044,
.003999,.000208,
.004004,-.000025,
.003996,-.000258,
.00398,-.00044,
.00483,-.00129,
.004897,-.001007,
.004947,-.000721,
.004981,-.000432,
.004997,-.000141,
.004997,.000149,
.00498,.00044,
.004946,.000729,
.004895,.001015,
.00483,.00129,
.00398,.00044,
0.0*
4,1,15,.00044,-.00398,
.000208,-.003999,
-.000025,-.004004,
-.000258,-.003996,
-.00044,-.00398,
-.00129,-.00483,
-.001007,-.004897,
-.000721,-.004947,
-.000432,-.004981,
-.000141,-.004997,
.000149,-.004997,
.00044,-.00498,
.000729,-.004946,
.001015,-.004895,
.00129,-.00483,
.00044,-.00398,
0.0*
4,1,15,-.00398,-.00044,
-.003999,-.000208,
-.004004,.000025,
-.003996,.000258,
-.00398,.00044,
-.00483,.00129,
-.004897,.001007,
-.004947,.000721,
-.004981,.000432,
-.004997,.000141,
-.004997,-.000149,
-.00498,-.00044,
-.004946,-.000729,
-.004895,-.001015,
-.00483,-.00129,
-.00398,-.00044,
0.0*
4,1,15,-.00044,.00398,
-.000208,.003999,
.000025,.004004,
.000258,.003996,
.00044,.00398,
.00129,.00483,
.001007,.004897,
.000721,.004947,
.000432,.004981,
.000141,.004997,
-.000149,.004997,
-.00044,.00498,
-.000729,.004946,
-.001015,.004895,
-.00129,.00483,
-.00044,.00398,
0.0*
%
%ADD17MACRO17*%
%ADD16C,.101*%
%ADD10C,.114*%
%ADD14C,.18*%
%ADD12C,.119*%
%ADD22C,.174*%
%ADD18C,.197*%
%AMMACRO21*
4,1,15,.00398,.00044,
.003999,.000208,
.004004,-.000025,
.003996,-.000258,
.00398,-.00044,
.00483,-.00129,
.004897,-.001007,
.004947,-.000721,
.004981,-.000432,
.004997,-.000141,
.004997,.000149,
.00498,.00044,
.004946,.000729,
.004895,.001015,
.00483,.00129,
.00398,.00044,
270.*
4,1,15,.00044,-.00398,
.000208,-.003999,
-.000025,-.004004,
-.000258,-.003996,
-.00044,-.00398,
-.00129,-.00483,
-.001007,-.004897,
-.000721,-.004947,
-.000432,-.004981,
-.000141,-.004997,
.000149,-.004997,
.00044,-.00498,
.000729,-.004946,
.001015,-.004895,
.00129,-.00483,
.00044,-.00398,
270.*
4,1,15,-.00398,-.00044,
-.003999,-.000208,
-.004004,.000025,
-.003996,.000258,
-.00398,.00044,
-.00483,.00129,
-.004897,.001007,
-.004947,.000721,
-.004981,.000432,
-.004997,.000141,
-.004997,-.000149,
-.00498,-.00044,
-.004946,-.000729,
-.004895,-.001015,
-.00483,-.00129,
-.00398,-.00044,
270.*
4,1,15,-.00044,.00398,
-.000208,.003999,
.000025,.004004,
.000258,.003996,
.00044,.00398,
.00129,.00483,
.001007,.004897,
.000721,.004947,
.000432,.004981,
.000141,.004997,
-.000149,.004997,
-.00044,.00498,
-.000729,.004946,
-.001015,.004895,
-.00129,.00483,
-.00044,.00398,
270.*
%
%ADD21MACRO21*%
%AMMACRO19*
4,1,15,.00398,.00044,
.003999,.000208,
.004004,-.000025,
.003996,-.000258,
.00398,-.00044,
.00483,-.00129,
.004897,-.001007,
.004947,-.000721,
.004981,-.000432,
.004997,-.000141,
.004997,.000149,
.00498,.00044,
.004946,.000729,
.004895,.001015,
.00483,.00129,
.00398,.00044,
180.*
4,1,15,.00044,-.00398,
.000208,-.003999,
-.000025,-.004004,
-.000258,-.003996,
-.00044,-.00398,
-.00129,-.00483,
-.001007,-.004897,
-.000721,-.004947,
-.000432,-.004981,
-.000141,-.004997,
.000149,-.004997,
.00044,-.00498,
.000729,-.004946,
.001015,-.004895,
.00129,-.00483,
.00044,-.00398,
180.*
4,1,15,-.00398,-.00044,
-.003999,-.000208,
-.004004,.000025,
-.003996,.000258,
-.00398,.00044,
-.00483,.00129,
-.004897,.001007,
-.004947,.000721,
-.004981,.000432,
-.004997,.000141,
-.004997,-.000149,
-.00498,-.00044,
-.004946,-.000729,
-.004895,-.001015,
-.00483,-.00129,
-.00398,-.00044,
180.*
4,1,15,-.00044,.00398,
-.000208,.003999,
.000025,.004004,
.000258,.003996,
.00044,.00398,
.00129,.00483,
.001007,.004897,
.000721,.004947,
.000432,.004981,
.000141,.004997,
-.000149,.004997,
-.00044,.00498,
-.000729,.004946,
-.001015,.004895,
-.00129,.00483,
-.00044,.00398,
180.*
%
%ADD19MACRO19*%
%ADD23C,.02*%
%ADD24C,.006*%
%ADD29C,.09704*%
%ADD28C,.11504*%
%ADD25O,.0802X.0462*%
%ADD30C,.17004*%
%ADD27O,.0812X.0462*%
%ADD26O,.0822X.0462*%
G75*
%LPD*%
G75*
G36*
G01X-6000Y-6000D02*
X1039465D01*
Y1998126D01*
X-6000D01*
Y-6000D01*
G37*
%LPC*%
G75*
G36*
G01X24206Y426804D02*
X24081Y423407D01*
X24083D01*
X24092Y423216D01*
G03X24111Y423005I2307J101D01*
G02X23797Y422814I-198J-28D01*
G03X19883Y424067I-3915J-5491D01*
G01X3213D01*
X3004Y424276D01*
Y819818D01*
X3213Y820027D01*
X19882D01*
G03Y833516I0J6745D01*
G01X3213D01*
X3004Y833725D01*
Y1194621D01*
X3214Y1194831D01*
X19882D01*
G03Y1208319I0J6744D01*
G01X3213D01*
X3004Y1208528D01*
Y1394621D01*
X3214Y1394831D01*
X19882D01*
G03Y1408319I0J6744D01*
G01X3213D01*
X3004Y1408528D01*
Y1804070D01*
X3213Y1804279D01*
X19882D01*
G03Y1817768I0J6744D01*
G01X3213D01*
X3004Y1817977D01*
Y1988189D01*
G02X3937Y1989122I933J0D01*
G01X1029528D01*
G02X1030461Y1988189I0J-933D01*
G01Y1686599D01*
X1028283Y1684421D01*
X1024211D01*
G03X1016287Y1676496I1J-7925D01*
G01Y1621265D01*
X1014109Y1619087D01*
X989744D01*
G03Y1608866I0J-5110D01*
G01X1014109D01*
X1016287Y1606688D01*
Y1433740D01*
G03X1024211Y1425815I7925J0D01*
G01X1028283D01*
X1030461Y1423637D01*
Y3937D01*
G02X1029528Y3004I-933J0D01*
G01X3937D01*
G02X3004Y3937I0J933D01*
G01Y210369D01*
X3214Y210579D01*
X19882D01*
G03Y224067I0J6744D01*
G01X3213D01*
X3004Y224276D01*
Y410369D01*
X3214Y410579D01*
X19882D01*
G03X25866Y420434I0J6744D01*
G02X26247Y421018I355J185D01*
G03X28694Y423060I152J2304D01*
G01X28714Y423237D01*
X28717D01*
X28842Y426635D01*
X28840D01*
X28831Y426826D01*
G03X24221Y426887I-2307J-106D01*
G01X24215Y426813D01*
X24206Y426804D01*
G37*
%LPD*%
G75*
G36*
G01X82886Y1748948D02*
X83033Y1752344D01*
G02X87649Y1752145I2308J-99D01*
G01X87502Y1748748D01*
G02X82886Y1748948I-2308J100D01*
G37*
G36*
G01X107093Y1739419D02*
X107082Y1739608D01*
X107080D01*
X107180Y1743607D01*
X107189Y1743616D01*
X107194Y1743692D01*
G02X111805Y1743681I2305J-143D01*
G01X111816Y1743492D01*
X111818D01*
X111718Y1739492D01*
X111715D01*
X111696Y1739313D01*
G02X107093Y1739419I-2297J238D01*
G37*
G36*
G01X48187Y1724823D02*
G02X43567I-2310J0D01*
G01Y1728478D01*
G02X48187Y1728477I2310J-1D01*
G01Y1724823D01*
G37*
G36*
G01X29660Y1642692D02*
G02X29593Y1647312I-34J2310D01*
G01X32993Y1647361D01*
G02X33059Y1642741I33J-2310D01*
G01X29660Y1642692D01*
G37*
G36*
G01X30219Y1509592D02*
G02X30012Y1514208I-104J2308D01*
G01X33409Y1514359D01*
G02X33615Y1509743I103J-2308D01*
G01X30219Y1509592D01*
G37*
G36*
G01X30485Y1460210D02*
G02X30272Y1464826I-106J2308D01*
G01X33809Y1464989D01*
G02X34021Y1460373I106J-2308D01*
G01X30485Y1460210D01*
G37*
G36*
G01X107245Y1440601D02*
G02X102625Y1440668I-2310J33D01*
G01X102689Y1444975D01*
G02X107309Y1444907I2310J-34D01*
G01X107245Y1440601D01*
G37*
G36*
G01X31903Y1430445D02*
X31745Y1430553D01*
X31744Y1430551D01*
X29037Y1432749D01*
X29039Y1432752D01*
X28910Y1432874D01*
G02X31955Y1436343I1590J1676D01*
G01X32110Y1436217D01*
X32116Y1436225D01*
X34668Y1434154D01*
Y1434142D01*
X34736Y1434083D01*
G02X31903Y1430445I-1529J-1732D01*
G37*
G36*
G01X119700Y1426200D02*
G02X115080Y1426201I-2310J1D01*
G01Y1429976D01*
G02X119700I2310J0D01*
G01Y1426200D01*
G37*
G36*
G01X31582Y1387198D02*
X31409Y1387257D01*
X31408Y1387255D01*
X27575Y1388922D01*
X27555Y1388942D01*
X27523Y1388957D01*
G02X29250Y1393235I977J2093D01*
G01X29423Y1393176D01*
X29424Y1393178D01*
X33258Y1391511D01*
X33257Y1391509D01*
X33421Y1391421D01*
G02X31582Y1387198I-1089J-2038D01*
G37*
G36*
G01X99536Y1373462D02*
G02X94922Y1373213I-2307J-125D01*
G01X94693Y1377476D01*
G02X99307Y1377724I2307J124D01*
G01X99536Y1373462D01*
G37*
G36*
G01X114719Y1357817D02*
G02X110161Y1358576I-2279J380D01*
G01X110720Y1361930D01*
G02X115278Y1361170I2279J-380D01*
G01X114719Y1357817D01*
G37*
G36*
G01X115810Y1344499D02*
G02X111190Y1344500I-2310J1D01*
G01Y1348154D01*
G02X115810I2310J0D01*
G01Y1344499D01*
G37*
G36*
G01X104660D02*
G02X100040Y1344500I-2310J1D01*
G01Y1348154D01*
G02X104660I2310J0D01*
G01Y1344499D01*
G37*
G36*
G01X111538Y1333315D02*
G02X106918I-2310J0D01*
G01Y1337091D01*
G02X111538Y1337090I2310J-1D01*
G01Y1333315D01*
G37*
G36*
G01X139791Y1077561D02*
G02X135171Y1077554I-2310J-3D01*
G01X135167Y1081174D01*
G02X139787Y1081180I2310J3D01*
G01Y1081174D01*
X139791Y1077561D01*
G37*
G36*
G01X126733Y1077522D02*
G02X122113Y1077523I-2310J1D01*
G01Y1081177D01*
G02X126733I2310J0D01*
G01Y1077522D01*
G37*
G36*
G01X126309Y1050650D02*
G02X121689I-2310J0D01*
G01Y1054051D01*
G02X126309Y1054050I2310J-1D01*
G01Y1050650D01*
G37*
G36*
G01X88693Y937322D02*
G02X84105Y936778I-2294J-272D01*
G01X83705Y940156D01*
G02X88293Y940701I2294J272D01*
G01X88693Y937322D01*
G37*
G36*
G01X111403Y928423D02*
G02X106795Y928078I-2304J-173D01*
G01X106541Y931485D01*
G02X111149Y931829I2304J172D01*
G01X111403Y928423D01*
G37*
G36*
G01X29997Y667446D02*
G02X25377Y667447I-2310J1D01*
G01Y671101D01*
G02X29997I2310J0D01*
G01Y667446D01*
G37*
G36*
G01X146548Y645355D02*
G02X141928Y645356I-2310J1D01*
G01Y649131D01*
G02X146548I2310J0D01*
G01Y645355D01*
G37*
G36*
G01X132021Y646825D02*
G02X130779Y642375I-621J-2225D01*
G01X127409Y643317D01*
X127408D01*
G02X128620Y647775I591J2233D01*
G01X132021Y646825D01*
G37*
G36*
G01X127809Y635549D02*
G02X123189Y635550I-2310J1D01*
G01Y638950D01*
G02X127809I2310J0D01*
G01Y635549D01*
G37*
G36*
G01X57689Y537547D02*
G02X62309Y537553I2310J3D01*
G01Y537547D01*
X62313Y534154D01*
G02X57693Y534147I-2310J-3D01*
G01X57689Y537547D01*
G37*
G36*
G01X88509Y532249D02*
G02X83889Y532250I-2310J1D01*
G01Y536025D01*
G02X88509I2310J0D01*
G01Y532249D01*
G37*
G36*
G01X28909Y525647D02*
G02X24289Y525648I-2310J1D01*
G01Y529302D01*
G02X28909I2310J0D01*
G01Y525647D01*
G37*
G36*
G01X38809Y517774D02*
G02X34189Y517775I-2310J1D01*
G01Y521550D01*
G02X38809I2310J0D01*
G01Y517774D01*
G37*
G36*
G01X28709Y501965D02*
G02X24089Y501966I-2310J1D01*
G01Y505741D01*
G02X28709I2310J0D01*
G01Y501965D01*
G37*
G36*
G01X62291Y486368D02*
X62391Y489768D01*
G02X67009Y489632I2309J-68D01*
G01X66909Y486244D01*
G02X62291Y486368I-2309J56D01*
G37*
G36*
G01X23990Y478372D02*
X23987Y478551D01*
X23984D01*
X24200Y481945D01*
X24202D01*
X24230Y482134D01*
G02X28824Y481830I2285J-337D01*
G01X28827Y481651D01*
X28830D01*
X28614Y478258D01*
X28604Y478248D01*
X28597Y478177D01*
G02X23990Y478372I-2298J227D01*
G37*
G36*
G01X62087Y474442D02*
G02X66707Y474450I2310J4D01*
G01Y474442D01*
X66713Y471051D01*
G02X62093Y471042I-2310J-5D01*
G01X62087Y474442D01*
G37*
G36*
G01X25191Y460155D02*
G03X25145Y460767I-279J287D01*
G02X24176Y462656I1341J1881D01*
G01X24189Y466258D01*
G02X28809Y466242I2310J-8D01*
G01X28796Y462641D01*
G02X28094Y460990I-2310J7D01*
G03X28140Y460378I279J-287D01*
G02X29096Y458740I-1341J-1881D01*
G01X29115Y458561D01*
X29118D01*
X29218Y454915D01*
X29210Y454907D01*
X29209Y454825D01*
G02X24602Y454607I-2310J24D01*
G01X24583Y454786D01*
X24580D01*
X24480Y458433D01*
X24482D01*
X24493Y458622D01*
G02X25191Y460155I2306J-125D01*
G37*
G36*
G01X28801Y439278D02*
G02X24183Y439423I-2309J73D01*
G01X24290Y442822D01*
G02X28908Y442676I2309J-73D01*
G01X28801Y439278D01*
G37*
G36*
G01X28609Y399600D02*
G02X23989Y399601I-2310J1D01*
G01Y403376D01*
G02X28609I2310J0D01*
G01Y399600D01*
G37*
G36*
G01Y383853D02*
G02X23989Y383854I-2310J1D01*
G01Y387629D01*
G02X28609I2310J0D01*
G01Y383853D01*
G37*
G36*
G01X88902Y126569D02*
G02X84296Y126931I-2303J181D01*
G01X84596Y130747D01*
G02X89202Y130386I2303J-181D01*
G01X88902Y126569D01*
G37*
G36*
G01X29831Y1671683D02*
X29868Y1671670D01*
X31469Y1671768D01*
X31504Y1671784D01*
G02X31763Y1667523I990J-2078D01*
G01X31726Y1667536D01*
X30125Y1667438D01*
X30090Y1667422D01*
G02X29831Y1671683I-990J2078D01*
G37*
G36*
G01X29128Y1663280D02*
X29153Y1663274D01*
X31331Y1663330D01*
X31356Y1663337D01*
G02X31471Y1658886I643J-2210D01*
G01X31446Y1658892D01*
X29268Y1658836D01*
X29243Y1658829D01*
G02X29128Y1663280I-643J2210D01*
G37*
G36*
G01X30984Y1626606D02*
X28932Y1627819D01*
X28906Y1627826D01*
G02X31159Y1631645I593J2224D01*
G01X31178Y1631625D01*
X33232Y1630412D01*
X33259Y1630405D01*
G02X31003Y1626586I-596J-2224D01*
G01X30984Y1626606D01*
G37*
G36*
G01X31654Y1611314D02*
X29544D01*
X29518Y1611307D01*
G02Y1615741I-619J2217D01*
G01X29544Y1615734D01*
X31654D01*
X31680Y1615741D01*
G02Y1611307I619J-2217D01*
G01X31654Y1611314D01*
G37*
G36*
G01X30330Y1569755D02*
X27102Y1569903D01*
X27099D01*
G02X27310Y1574499I23J2302D01*
G01X27313D01*
X30540Y1574351D01*
X30543D01*
G02X30333Y1569755I-22J-2302D01*
G01X30330D01*
G37*
G36*
G01X29782Y1518465D02*
X29789Y1518491D01*
Y1520855D01*
X29782Y1520881D01*
G02X34216I2217J619D01*
G01X34209Y1520855D01*
Y1518491D01*
X34216Y1518465D01*
G02X29782I-2217J-619D01*
G37*
G36*
G01X33348Y1479670D02*
X31669Y1479847D01*
X31632Y1479837D01*
G02X32081Y1484082I-633J2213D01*
G01X32116Y1484063D01*
X33794Y1483886D01*
X33832Y1483896D01*
G02X33383Y1479651I633J-2213D01*
G01X33348Y1479670D01*
G37*
G36*
G01X29485Y1450459D02*
X29523Y1450445D01*
X31080Y1450515D01*
X31116Y1450532D01*
G02X31306Y1446285I978J-2084D01*
G01X31268Y1446299D01*
X29711Y1446229D01*
X29675Y1446212D01*
G02X29485Y1450459I-978J2084D01*
G37*
G36*
G01X29054Y1413851D02*
Y1413859D01*
X32505Y1413777D01*
X32512Y1413770D01*
X32587Y1413766D01*
G02X32396Y1409167I-136J-2298D01*
G01Y1409159D01*
X28944Y1409241D01*
Y1409242D01*
X28764Y1409260D01*
G02X29054Y1413851I236J2290D01*
G37*
G36*
G01X27808Y1371991D02*
Y1371987D01*
X27857Y1368569D01*
Y1368566D01*
G02X23257Y1368501I-2299J-120D01*
G01Y1368505D01*
X23208Y1371922D01*
Y1371926D01*
G02X27808Y1371991I2299J120D01*
G37*
G36*
G01X89190Y1346539D02*
Y1342952D01*
G02X84590I-2300J-92D01*
G01Y1346543D01*
G02X89190I2300J92D01*
G01Y1346539D01*
G37*
G36*
G01X52602Y699187D02*
Y699183D01*
X52706Y695966D01*
Y695962D01*
G02X48108Y695814I-2296J-161D01*
G01Y695818D01*
X48004Y699034D01*
Y699038D01*
G02X52602Y699187I2296J163D01*
G37*
G36*
G01X24435Y651912D02*
X24432Y652089D01*
X24431D01*
X24693Y656685D01*
X24720Y656872D01*
G02X29301Y656595I2279J-322D01*
G01X29304Y656418D01*
X29305D01*
X29043Y651826D01*
X29042D01*
X29019Y651652D01*
G02X24435Y651912I-2282J305D01*
G37*
G36*
G01X28868Y639508D02*
Y636042D01*
G02X24268I-2300J-92D01*
G01Y639512D01*
G02X28868I2300J92D01*
G01Y639508D01*
G37*
G36*
G01X29799Y623761D02*
Y620295D01*
G02X25199I-2300J-92D01*
G01Y623765D01*
G02X29799I2300J92D01*
G01Y623761D01*
G37*
G36*
G01X117986Y129129D02*
Y126894D01*
X118001Y126857D01*
G02X113751I-2125J-884D01*
G01X113766Y126894D01*
Y129129D01*
X113751Y129166D01*
G02X118001I2125J884D01*
G01X117986Y129129D01*
G37*
G36*
G01X760749Y97239D02*
Y179348D01*
G02Y184552I50J2602D01*
G01Y732506D01*
G02Y735494I1751J1494D01*
G01Y795233D01*
G02Y797467I2350J1117D01*
G01Y1092954D01*
X760581Y1092982D01*
G02Y1098118I418J2568D01*
G01X760749Y1098146D01*
Y1333624D01*
G02Y1337476I1750J1926D01*
G01Y1351124D01*
G02Y1354976I1750J1926D01*
G01Y1887832D01*
X760745Y1887851D01*
G02Y1888849I2554J499D01*
G01X760749Y1888868D01*
Y1908861D01*
X778188Y1926300D01*
X869802D01*
X869836Y1926458D01*
G02X874336I2250J-486D01*
G01X874370Y1926300D01*
X947310D01*
X964249Y1909361D01*
Y1641495D01*
X964413Y1641465D01*
G02Y1636935I-413J-2265D01*
G01X964249Y1636905D01*
Y1579323D01*
X964253Y1579304D01*
G02Y1578296I-2553J-504D01*
G01X964249Y1578277D01*
Y1573519D01*
G02Y1571281I-2349J-1119D01*
G01Y1523519D01*
G02Y1521281I-2349J-1119D01*
G01Y1517467D01*
G02Y1514533I-2149J-1467D01*
G01Y1467809D01*
G02Y1465191I-2249J-1309D01*
G01Y1462904D01*
G02Y1459696I-2049J-1604D01*
G01Y1458404D01*
G02Y1455196I-2049J-1604D01*
G01Y1453404D01*
G02Y1450196I-2049J-1604D01*
G01Y1448904D01*
G02Y1445696I-2049J-1604D01*
G01Y1442927D01*
G02X964310Y1439131I-1749J-1927D01*
G01X964249Y1439072D01*
Y1438428D01*
X964310Y1438369D01*
G02X964249Y1434573I-1810J-1869D01*
G01Y134239D01*
X907310Y77300D01*
X780688D01*
X760749Y97239D01*
G37*
G36*
G01X160585Y641364D02*
X160749Y641394D01*
Y645739D01*
X121749Y684739D01*
Y776361D01*
X154749Y809361D01*
Y835741D01*
X154569Y835760D01*
G02X152732Y839064I230J2290D01*
G01X152795Y839193D01*
X150749Y841239D01*
Y923361D01*
X154749Y927361D01*
Y984024D01*
G02Y987876I1750J1926D01*
G01Y999102D01*
G02Y1006174I3322J3536D01*
G01Y1074239D01*
X112808Y1116180D01*
G02X109006Y1119723I-1809J1870D01*
G01X109124Y1119864D01*
X107749Y1121239D01*
Y1228861D01*
X154249Y1275361D01*
Y1405162D01*
G02Y1411138I3822J2988D01*
G01Y1424239D01*
X101071Y1477417D01*
X100965Y1477396D01*
G02X99625Y1481780I-466J2254D01*
G01X99749Y1481831D01*
Y1534402D01*
G02X98803Y1537595I1051J2048D01*
G03X98731Y1537866I-174J99D01*
G02X99577Y1542129I1168J1984D01*
G01X99749Y1542154D01*
Y1544356D01*
X99585Y1544386D01*
G02Y1548914I415J2264D01*
G01X99749Y1548944D01*
Y1587361D01*
X154249Y1641861D01*
Y1783739D01*
X114188Y1823800D01*
X97278D01*
X97251Y1823792D01*
G02X95949I-651J2208D01*
G01X95922Y1823800D01*
X83688D01*
X73749Y1833739D01*
Y1941861D01*
X82188Y1950300D01*
X192810D01*
X236566Y1906544D01*
G03X237249Y1906827I283J283D01*
G01Y1937861D01*
X243188Y1943800D01*
X277810D01*
X290310Y1931300D01*
X521310D01*
X551249Y1901361D01*
Y1304680D01*
G02Y1301020I-1850J-1830D01*
G01Y1295680D01*
G02Y1292020I-1850J-1830D01*
G01Y1276680D01*
G02Y1273020I-1850J-1830D01*
G01Y1268227D01*
X551260Y1268195D01*
G02Y1266505I-2461J-845D01*
G01X551249Y1266473D01*
Y1253727D01*
X551260Y1253695D01*
G02Y1252005I-2461J-845D01*
G01X551249Y1251973D01*
Y1117357D01*
G02Y1114743I-2250J-1307D01*
G01Y712332D01*
G02Y707768I-1250J-2282D01*
G01Y96739D01*
X540310Y85800D01*
X388310D01*
X338310Y35800D01*
X139688D01*
X124249Y51239D01*
Y149861D01*
X144438Y170050D01*
X117749Y196739D01*
Y389861D01*
X123543Y395655D01*
X123527Y395755D01*
G02X126494Y398722I2572J395D01*
G01X126594Y398706D01*
X153749Y425861D01*
Y443269D01*
X153593Y443305D01*
G02Y447795I508J2245D01*
G01X153749Y447831D01*
Y473917D01*
X153588Y473949D01*
G02Y479051I512J2551D01*
G01X153749Y479083D01*
Y526652D01*
X153588Y526685D01*
G02Y531787I511J2551D01*
G01X153749Y531820D01*
Y594922D01*
G02Y599330I4322J2204D01*
G01Y602861D01*
X160749Y609861D01*
Y621475D01*
G02Y625325I1751J1925D01*
G01Y636806D01*
X160585Y636836D01*
G02Y641364I415J2264D01*
G37*
G54D29*
X78150Y28858D03*
Y178464D03*
Y434370D03*
Y583976D03*
Y839882D03*
Y989488D03*
Y1245394D03*
Y1395000D03*
Y1650906D03*
Y1800512D03*
X158071Y1963268D03*
X886417D03*
G54D28*
X9843Y153168D03*
Y265767D03*
Y353144D03*
Y717711D03*
Y762617D03*
Y875216D03*
Y1137420D03*
Y1250019D03*
Y1337396D03*
Y1701963D03*
Y1746869D03*
Y1859468D03*
G54D25*
X45300Y1737100D03*
X97200Y513400D03*
G54D30*
X1019291Y1416024D03*
Y1694212D03*
G54D27*
X78749Y664550D03*
G54D26*
X32299Y1497550D03*
%LPC*%
G75*
G36*
G01X155249Y602239D02*
X162249Y609239D01*
Y637166D01*
G03Y641034I-1249J1934D01*
G01Y646361D01*
X123249Y685361D01*
Y775739D01*
X156249Y808739D01*
Y836262D01*
G03X154045Y840225I-1450J1788D01*
G01X153926Y840184D01*
X152249Y841861D01*
Y922739D01*
X156249Y926739D01*
Y966503D01*
G03Y969995I-1500J1746D01*
G01Y977403D01*
G03Y980895I-1500J1746D01*
G01Y997583D01*
G02X156757Y997968I400J0D01*
G03Y1007308I1314J4670D01*
G02X156249Y1007693I-108J385D01*
G01Y1074861D01*
X113555Y1117555D01*
X113571Y1117655D01*
G03X110604Y1120622I-2572J395D01*
G01X110504Y1120606D01*
X109249Y1121861D01*
Y1194063D01*
X109253Y1194083D01*
G03Y1195017I-2254J467D01*
G01X109249Y1195037D01*
Y1228239D01*
X155749Y1274739D01*
Y1403263D01*
G02X156295Y1403635I400J0D01*
G03Y1412665I1776J4515D01*
G02X155749Y1413037I-146J372D01*
G01Y1424861D01*
X102345Y1478265D01*
X102433Y1478401D01*
G03X101373Y1481780I-1934J1249D01*
G01X101249Y1481831D01*
Y1534187D01*
X101397Y1534227D01*
G03X101968Y1538434I-597J2223D01*
G02X101896Y1538705I102J172D01*
G03X101249Y1541715I-1997J1145D01*
G01Y1544716D01*
G03Y1548584I-1249J1934D01*
G01Y1586739D01*
X155749Y1641239D01*
Y1784361D01*
X114810Y1825300D01*
X84310D01*
X75249Y1834361D01*
Y1941239D01*
X82810Y1948800D01*
X192188D01*
X266688Y1874300D01*
X323188D01*
X331749Y1865739D01*
Y1594361D01*
X323188Y1585800D01*
X277188D01*
X256749Y1565361D01*
Y1502739D01*
X266688Y1492800D01*
X320688D01*
X329249Y1484239D01*
Y1212861D01*
X314688Y1198300D01*
X269188D01*
X256249Y1185361D01*
Y1136739D01*
X262688Y1130300D01*
X318688D01*
X333249Y1115739D01*
Y789861D01*
X324188Y780800D01*
X284188D01*
X264249Y760861D01*
Y701739D01*
X269688Y696300D01*
X314688D01*
X333249Y677739D01*
Y485646D01*
X333081Y485618D01*
G03Y480482I418J-2568D01*
G01X333249Y480454D01*
Y385361D01*
X314688Y366800D01*
X290188D01*
X276188Y352800D01*
X261188D01*
X255749Y347361D01*
Y292739D01*
X264688Y283800D01*
X303688D01*
X318249Y269239D01*
Y196861D01*
X316861Y195473D01*
X316810Y195459D01*
G03X314990Y193639I689J-2509D01*
G01X314976Y193588D01*
X292188Y170800D01*
X154292D01*
G03X154108I-92J-2300D01*
G01X145810D01*
X119249Y197361D01*
Y389239D01*
X124285Y394275D01*
X124426Y394157D01*
G03X128092Y397823I1673J1993D01*
G01X127974Y397964D01*
X155249Y425239D01*
Y426047D01*
G03Y428941I-1790J1447D01*
G01Y443555D01*
G03Y447545I-1148J1995D01*
G01Y474165D01*
G03Y478835I-1149J2335D01*
G01Y500624D01*
G03Y504476I-1750J1926D01*
G01Y526902D01*
G03Y531570I-1150J2334D01*
G01Y592466D01*
G02X155833Y592821I400J0D01*
G03Y601431I2238J4305D01*
G02X155249Y601786I-184J355D01*
G01Y602239D01*
G37*
G36*
G01X334749Y1116361D02*
X319310Y1131800D01*
X263310D01*
X257749Y1137361D01*
Y1184739D01*
X269810Y1196800D01*
X315310D01*
X330749Y1212239D01*
Y1484861D01*
X321310Y1494300D01*
X267310D01*
X258249Y1503361D01*
Y1564739D01*
X277810Y1584300D01*
X323810D01*
X333249Y1593739D01*
Y1866361D01*
X323810Y1875800D01*
X267310D01*
X238749Y1904361D01*
Y1937239D01*
X243810Y1942300D01*
X277188D01*
X289688Y1929800D01*
X520688D01*
X549749Y1900739D01*
Y1603067D01*
G03Y1600833I2350J-1117D01*
G01Y1577527D01*
X549738Y1577495D01*
G03Y1575805I2461J-845D01*
G01X549749Y1575773D01*
Y712646D01*
X549581Y712618D01*
G03Y707482I418J-2568D01*
G01X549749Y707454D01*
Y97361D01*
X539688Y87300D01*
X525622D01*
G03X522176I-1723J-1950D01*
G01X387688D01*
X337688Y37300D01*
X287673D01*
G03X285533I-1070J-2372D01*
G01X140310D01*
X125749Y51861D01*
Y138743D01*
G03Y141357I-2250J1307D01*
G01Y147743D01*
G03X126071Y149445I-2250J1307D01*
G01X126055Y149545D01*
X145810Y169300D01*
X205782D01*
G03X208016I1117J2350D01*
G01X292810D01*
X319749Y196239D01*
Y269861D01*
X304310Y285300D01*
X265310D01*
X257249Y293361D01*
Y346739D01*
X261810Y351300D01*
X276810D01*
X290810Y365300D01*
X315310D01*
X334749Y384739D01*
Y480768D01*
G03Y485332I-1250J2282D01*
G01Y678361D01*
X334602Y678508D01*
X334601Y678589D01*
G03X332038Y681152I-2602J-39D01*
G01X331957Y681153D01*
X315310Y697800D01*
X270310D01*
X265749Y702361D01*
Y760239D01*
X284810Y779300D01*
X324810D01*
X334749Y789239D01*
Y981438D01*
G03Y985462I-1650J2012D01*
G01Y1116361D01*
G37*
G36*
G01X771051Y1917041D02*
X775315Y1921305D01*
X775337Y1921318D01*
G03X776231Y1922212I-1338J2232D01*
G01X776244Y1922234D01*
X778810Y1924800D01*
X870105D01*
G03X874067I1981J1172D01*
G01X946688D01*
X962749Y1908739D01*
Y1742098D01*
G03Y1741902I2600J-98D01*
G01Y1641132D01*
G03Y1637268I1251J-1932D01*
G01Y1411711D01*
G03Y1407689I1651J-2011D01*
G01Y1325467D01*
G03Y1323233I2350J-1117D01*
G01Y134861D01*
X906688Y78800D01*
X781310D01*
X762249Y97861D01*
Y179789D01*
G03Y184111I-1450J2161D01*
G01Y1093268D01*
G03Y1097832I-1250J2282D01*
G01Y1908239D01*
X769008Y1914998D01*
X769064Y1915010D01*
G03X771039Y1916985I-565J2540D01*
G01X771051Y1917041D01*
G37*
%LPD*%
G75*
G36*
G01X125905Y1874118D02*
X125908D01*
X125709Y1870724D01*
X125700Y1870715D01*
X125693Y1870643D01*
G02X121083Y1870817I-2300J216D01*
G01X121080Y1870995D01*
X121077D01*
X121276Y1874390D01*
X121278D01*
X121305Y1874580D01*
G02X125902Y1874296I2287J-325D01*
G01X125905Y1874118D01*
G37*
G36*
G01X140309Y1861496D02*
G02X135689Y1861497I-2310J1D01*
G01Y1865151D01*
G02X140309I2310J0D01*
G01Y1861496D01*
G37*
G36*
G01X145216Y1460063D02*
X145219D01*
X145318Y1456437D01*
X145310Y1456429D01*
X145309Y1456347D01*
G02X140702Y1456131I-2310J26D01*
G01X140683Y1456310D01*
X140680D01*
X140581Y1459937D01*
X140583D01*
X140594Y1460126D01*
G02X145197Y1460242I2306J-127D01*
G01X145216Y1460063D01*
G37*
G36*
G01X121805Y1466185D02*
X122081Y1468591D01*
X122071Y1468628D01*
G02X126312Y1468141I2219J613D01*
G01X126293Y1468106D01*
X126017Y1465700D01*
X126027Y1465663D01*
G02X121786Y1466151I-2219J-613D01*
G01X121805Y1466185D01*
G37*
G36*
G01X124699Y252950D02*
X124702D01*
X125104Y249412D01*
X125102D01*
X125108Y249225D01*
G02X120532Y248709I-2309J-75D01*
G01X120497Y248888D01*
X120494D01*
X120092Y252425D01*
X120100Y252433D01*
X120093Y252524D01*
G02X124664Y253129I2304J163D01*
G01X124699Y252950D01*
G37*
G36*
G01X152309Y239728D02*
G02X147689Y239729I-2310J1D01*
G01Y243504D01*
G02X152309I2310J0D01*
G01Y239728D01*
G37*
G36*
G01X864604Y1865615D02*
G02X869224I2310J0D01*
G01Y1861839D01*
G02X864604Y1861840I-2310J1D01*
G01Y1865615D01*
G37*
G36*
G01X850085Y1868746D02*
G02X850113Y1873366I14J2310D01*
G01X853512Y1873346D01*
G02X853485Y1868726I-14J-2310D01*
G01X850085Y1868746D01*
G37*
G36*
G01X875740Y1456319D02*
X875738D01*
X875537Y1459860D01*
X875540D01*
X875544Y1460038D01*
G02X880159Y1460121I2309J-48D01*
G01X880170Y1459922D01*
X880180D01*
X880370Y1456582D01*
X880362Y1456574D01*
X880363Y1456489D01*
G02X875767Y1456129I-2309J-39D01*
G01X875740Y1456319D01*
G37*
G36*
G01X848851Y1464092D02*
G02X848926Y1468712I38J2310D01*
G01X852326Y1468656D01*
G02X852250Y1464036I-38J-2310D01*
G01X848851Y1464092D01*
G37*
G36*
G01X875661Y1054302D02*
G02X880267Y1054668I2303J183D01*
G01X880536Y1051279D01*
G02X875930Y1050912I-2303J-183D01*
G01X875661Y1054302D01*
G37*
G36*
G01X847200Y1059182D02*
G02X847266Y1063802I33J2310D01*
G01X850865Y1063751D01*
G02X850800Y1059131I-32J-2310D01*
G01X847200Y1059182D01*
G37*
G36*
G01X851129Y657742D02*
G02X851214Y653122I42J-2310D01*
G01X847814Y653060D01*
G02X847730Y657680I-42J2310D01*
G01X851129Y657742D01*
G37*
G36*
G01X876286Y649348D02*
G02X880906I2310J0D01*
G01Y645572D01*
G02X876286Y645573I-2310J1D01*
G01Y649348D01*
G37*
G36*
G01X875768Y243878D02*
G02X880388I2310J0D01*
G01Y240102D01*
G02X875768Y240103I-2310J1D01*
G01Y243878D01*
G37*
G36*
G01X847834Y247730D02*
G02X847923Y252350I44J2310D01*
G01X851323Y252284D01*
G02X851233Y247664I-45J-2310D01*
G01X847834Y247730D01*
G37*
G54D29*
X158071Y1813662D03*
Y1557756D03*
Y1152244D03*
Y746732D03*
Y341220D03*
Y191614D03*
X886417Y1813662D03*
Y1557756D03*
Y1408150D03*
Y1152244D03*
Y1002638D03*
Y746732D03*
Y597126D03*
Y341220D03*
Y191614D03*
G54D15*
X68898Y17047D03*
Y190275D03*
Y422559D03*
Y595787D03*
Y828071D03*
Y1001299D03*
Y1233583D03*
Y1406811D03*
Y1639095D03*
Y1812323D03*
X167323Y179803D03*
Y353031D03*
Y585315D03*
Y758543D03*
Y990827D03*
Y1164055D03*
Y1396339D03*
Y1569567D03*
Y1801851D03*
Y1975079D03*
X895669Y179803D03*
Y353031D03*
Y585315D03*
Y758543D03*
Y990827D03*
Y1164055D03*
Y1396339D03*
Y1569567D03*
Y1801851D03*
Y1975079D03*
G54D13*
X8750Y1086250D03*
X8499Y1937550D03*
X5303Y1947050D03*
X11703Y1951946D03*
X93999Y58550D03*
X92900Y66128D03*
X89800Y132400D03*
X92999Y86128D03*
Y96128D03*
X74499Y84050D03*
Y80650D03*
X86899Y130567D03*
X86599Y126750D03*
X74999Y74050D03*
Y70550D03*
X78700Y70700D03*
Y74200D03*
X15750Y102250D03*
X41999Y200050D03*
X65999Y216050D03*
X95350Y204550D03*
X89800Y208550D03*
X24300Y247300D03*
X29699Y388484D03*
X29599Y382884D03*
X29999Y398684D03*
X23499Y397579D03*
X23399Y373931D03*
Y389679D03*
X23499Y381831D03*
X26299Y383854D03*
Y387629D03*
X28100Y374000D03*
X26492Y439350D03*
X26599Y442749D03*
X26299Y399601D03*
Y403376D03*
Y478404D03*
X26899Y454850D03*
X26515Y481798D03*
X26799Y458497D03*
X26486Y462648D03*
X26499Y466250D03*
X64403Y471046D03*
X64397Y474446D03*
X26524Y426720D03*
X26399Y423322D03*
X29899Y404384D03*
X28900Y429200D03*
X29365Y421169D03*
X29500Y460800D03*
X28700Y451900D03*
X28800Y436700D03*
X28700Y445700D03*
X68000Y475600D03*
X67800Y469900D03*
X23499Y468447D03*
X23399Y476295D03*
Y444799D03*
X23499Y452699D03*
X23399Y460547D03*
Y429051D03*
X23499Y436951D03*
X23600Y405700D03*
X77499Y469550D03*
X61400Y452600D03*
X35900Y412600D03*
X65000Y455500D03*
X28900Y417800D03*
X39217Y554750D03*
X42867Y548450D03*
X43099Y555850D03*
X33699Y561850D03*
X46299Y552950D03*
X36499Y517775D03*
Y521550D03*
X26399Y501966D03*
Y505741D03*
X64600Y486300D03*
X64700Y489700D03*
X33307Y557938D03*
X26199Y547176D03*
X93200Y510500D03*
X83700Y529500D03*
X28600Y508500D03*
X35300Y524800D03*
X38400Y514900D03*
X88999Y538050D03*
X68900Y490600D03*
X68700Y485200D03*
X28600Y499300D03*
X26900Y532800D03*
X63499Y538550D03*
Y533050D03*
X22800Y539600D03*
X23499Y515691D03*
X23399Y523539D03*
X23499Y531439D03*
X23399Y492043D03*
X23499Y499943D03*
X23399Y507791D03*
X23499Y484195D03*
X77999Y493050D03*
X77499Y502550D03*
X29999Y557150D03*
X26599Y525648D03*
X95500Y513400D03*
X26599Y529302D03*
X60003Y534150D03*
X86199Y536025D03*
X59999Y537550D03*
X86199Y532250D03*
X65599Y514250D03*
X49799Y559150D03*
X68000Y546500D03*
X72500Y545000D03*
X27199Y539600D03*
X42202Y608195D03*
X39600Y626984D03*
X41400Y611500D03*
X42709Y625607D03*
X38300Y633800D03*
X41500Y642800D03*
X27499Y620203D03*
Y623857D03*
X36499Y566350D03*
X42599Y567850D03*
X32800Y578200D03*
X47543Y578340D03*
X44959Y575756D03*
X30712Y624971D03*
X29999Y640550D03*
X60076Y595777D03*
X55499Y595650D03*
X29819Y634951D03*
X26869Y616861D03*
X23399Y641649D03*
X23499Y618053D03*
X23799Y625950D03*
X23499Y633801D03*
X23999Y609250D03*
X22978Y588571D03*
X22699Y577950D03*
X22999Y565550D03*
X57800Y634300D03*
X34976Y619250D03*
X44900Y642800D03*
X26568Y635950D03*
Y639604D03*
X47101Y632355D03*
X28000Y578500D03*
X25581Y567763D03*
X47626Y611300D03*
X45701Y607700D03*
X27699Y573750D03*
X82499Y627050D03*
X26800Y611500D03*
X41500Y635000D03*
X52500D03*
X48999Y642900D03*
X81251Y607249D03*
Y619251D03*
X28808Y593150D03*
X28700Y596549D03*
X32200Y603710D03*
X31598Y607102D03*
X80499Y664550D03*
X30999Y656250D03*
X29999Y694550D03*
X30999Y650550D03*
X81999Y668050D03*
X74499Y662050D03*
X25999Y694870D03*
X23999Y689050D03*
X23499Y665297D03*
X23699Y673150D03*
X23499Y681045D03*
Y649549D03*
X23725Y657471D03*
X78499Y654050D03*
X26737Y651957D03*
X26999Y656550D03*
X27687Y667447D03*
Y671101D03*
X76999Y664550D03*
X27700Y682700D03*
X50410Y695801D03*
X50300Y699200D03*
X44046Y799554D03*
X32800Y803050D03*
X46887Y803413D03*
X37416Y799033D03*
X37099Y811350D03*
X51100Y806300D03*
X49900Y813200D03*
X56281Y801350D03*
X27299Y783550D03*
X35300Y789375D03*
X90700Y792900D03*
X35559Y795112D03*
X45100Y793100D03*
X37216Y807951D03*
X76540Y850938D03*
X29299Y836901D03*
X75500Y847700D03*
X49300Y836500D03*
X46700Y820100D03*
X40400Y840792D03*
X89000Y816500D03*
X48346Y844529D03*
X58699Y837250D03*
X26299Y815050D03*
X92999Y868550D03*
X92499Y876550D03*
X68860Y838706D03*
X90000Y826000D03*
X54074Y815750D03*
X69499Y842950D03*
X62405Y820300D03*
X63499Y843050D03*
X90500Y831500D03*
X31699Y814350D03*
X65500Y817700D03*
X23299Y863050D03*
X26662Y861550D03*
X39649Y822000D03*
X80500Y817000D03*
X74220Y854150D03*
X72362Y849550D03*
X25000Y858100D03*
X46576Y832951D03*
X29600Y854000D03*
X24000Y853500D03*
X89400Y935400D03*
X89499Y942850D03*
X94999Y901550D03*
X85999Y940429D03*
X86399Y937050D03*
X29000Y896500D03*
X72000Y1013400D03*
X63273Y1023974D03*
X90000Y993100D03*
X92600Y996100D03*
X20400Y1048300D03*
X66499Y1025050D03*
X75900Y1019100D03*
X63500Y1029600D03*
X88000Y1008500D03*
X75500Y1012261D03*
X80000Y1090500D03*
X80500Y1097550D03*
Y1104500D03*
X76999Y1196550D03*
X21817Y1156317D03*
X78499Y1273550D03*
X78613Y1282664D03*
X78779Y1302664D03*
X91279Y1340642D03*
X89999Y1348050D03*
X27499Y1387550D03*
X24499Y1389663D03*
X22851Y1374169D03*
X22999Y1366050D03*
X23700Y1354600D03*
X23499Y1381500D03*
X78779Y1312664D03*
X86165Y1339050D03*
X25507Y1372045D03*
X25558Y1368447D03*
X86890Y1346635D03*
Y1342860D03*
X28499Y1391050D03*
X32333Y1389383D03*
X20999Y1352050D03*
Y1320550D03*
X77758Y1357742D03*
X25000D03*
X30378Y1462518D03*
X33915Y1462681D03*
X32094Y1448448D03*
X28697Y1448296D03*
X33000Y1393000D03*
X33400Y1408100D03*
X36198Y1446749D03*
X26800Y1443800D03*
X30600Y1415100D03*
X30999Y1438050D03*
X27999Y1430050D03*
X29100Y1459200D03*
X34200Y1466200D03*
X23028Y1468579D03*
X23499Y1460550D03*
X22999Y1453050D03*
X23499Y1445050D03*
X22999Y1437050D03*
X23999Y1429050D03*
X23499Y1421550D03*
X23999Y1413550D03*
X32451Y1411468D03*
X28999Y1411550D03*
X33206Y1432352D03*
X30499Y1434550D03*
X30500Y1395500D03*
X76000Y1431100D03*
X34896Y1555730D03*
X34099Y1497550D03*
X30499D03*
X80043Y1544691D03*
X83932Y1544705D03*
X29631Y1533063D03*
X31999Y1517846D03*
Y1521500D03*
X46700Y1546793D03*
X34465Y1481683D03*
X30999Y1482050D03*
X44299Y1550950D03*
X96200Y1550100D03*
X32700Y1485200D03*
X28999Y1478050D03*
X27100Y1494300D03*
X34900Y1501000D03*
X35400Y1522200D03*
X35999Y1514550D03*
X29600Y1515300D03*
X24423Y1527123D03*
X22999Y1500050D03*
Y1515550D03*
X23799Y1508050D03*
X24499Y1492050D03*
X23599Y1476350D03*
X23277Y1484050D03*
X25247Y1546912D03*
X37999Y1530900D03*
X38500Y1534600D03*
X32099Y1535550D03*
X30115Y1511900D03*
X33512Y1512051D03*
X90324Y1538800D03*
X26705Y1534795D03*
X30199Y1545450D03*
X24199Y1523700D03*
X79000Y1555500D03*
X82429D03*
X36340Y1558809D03*
X78600Y1561900D03*
X29499Y1630050D03*
X75000Y1561800D03*
X28899Y1613524D03*
X42199Y1601050D03*
X38208Y1569841D03*
X25521Y1563350D03*
X30520Y1572049D03*
X32299Y1613524D03*
X24900Y1569500D03*
X31149Y1568300D03*
X26999Y1610550D03*
X34884Y1615734D03*
X32199Y1633124D03*
X34816Y1630953D03*
X22999Y1626050D03*
X23499Y1634050D03*
Y1618050D03*
X22699Y1594224D03*
X23499Y1610050D03*
Y1602050D03*
X23608Y1572653D03*
X24323Y1559950D03*
X31099Y1595350D03*
X32663Y1628181D03*
X27123Y1572205D03*
X33599Y1600200D03*
X74800Y1584700D03*
X74700Y1574600D03*
X39000Y1573500D03*
X89373Y1561073D03*
X85600Y1561500D03*
X80400Y1571766D03*
X82329Y1568117D03*
X31999Y1661127D03*
X28600Y1661039D03*
X29626Y1645002D03*
X33026Y1645051D03*
X95499Y1665418D03*
X33100Y1648500D03*
X47400Y1721700D03*
X34699Y1663300D03*
X27499Y1657050D03*
X26785Y1642089D03*
X22999Y1665550D03*
X92873Y1708176D03*
X24244Y1681868D03*
X22864Y1673550D03*
X23499Y1657050D03*
X23999Y1649550D03*
X23415Y1641634D03*
X92479Y1718176D03*
X78100Y1688189D03*
X92900Y1678176D03*
X93999Y1703050D03*
X74500Y1692000D03*
X21600Y1702900D03*
X32700Y1673300D03*
X32494Y1669706D03*
X29100Y1669500D03*
X30274Y1787238D03*
X85599Y1797350D03*
X38878Y1799571D03*
X47899Y1798650D03*
X36300Y1805123D03*
X35675Y1783450D03*
X39324Y1780623D03*
X39000Y1750800D03*
X43751Y1780559D03*
X42275Y1754000D03*
X48049Y1791450D03*
X40400Y1735600D03*
X47900Y1731300D03*
X47800Y1740500D03*
X89306Y1746856D03*
X89499Y1753575D03*
X85341Y1752245D03*
X85194Y1748848D03*
X46999Y1779550D03*
X37699Y1789850D03*
X46199Y1783050D03*
X74400Y1778100D03*
X38094Y1785840D03*
X41200Y1747050D03*
X42199Y1792250D03*
X37574Y1794050D03*
X45799Y1757650D03*
X46799Y1794900D03*
X47440Y1761391D03*
X31811Y1790271D03*
X47400Y1765250D03*
X43559Y1767884D03*
X40478Y1795820D03*
X32099Y1797150D03*
X47604Y1769005D03*
X45782Y1771877D03*
X47499Y1775350D03*
X45877Y1728477D03*
Y1724823D03*
X47000Y1737100D03*
X43600D03*
X28550Y1828153D03*
X29599Y1844350D03*
X29899Y1821050D03*
X34099Y1822850D03*
X60449Y1842550D03*
X80099Y1817250D03*
X28123Y1831527D03*
X35876Y1812350D03*
X34129Y1815267D03*
X86649Y1817100D03*
X61009Y1822340D03*
X36532Y1825352D03*
X36399Y1828750D03*
X26099Y1824950D03*
X25999Y1842550D03*
X46499Y1836550D03*
X47166Y1839884D03*
X90000Y1827900D03*
X43099Y1833850D03*
X39699D03*
X93500Y1827900D03*
X40500Y1863000D03*
X22367Y1836633D03*
X50299Y1946650D03*
X53999D03*
X42532Y1946783D03*
X44399Y1942250D03*
X38703Y1946754D03*
X34799Y1946750D03*
X46565Y1946703D03*
X44368Y1951450D03*
X45999Y1971450D03*
X28799Y1919060D03*
X14999Y1940050D03*
X15099Y1944050D03*
X50499Y1961550D03*
X14999Y1936050D03*
X17499Y1961050D03*
X43462Y1961160D03*
X32999Y1960555D03*
X23030Y1922038D03*
X25499Y1956050D03*
X42499Y1902550D03*
X48499Y1897050D03*
X26765Y1921945D03*
X57999Y1891050D03*
X31799Y1979050D03*
X112999Y124050D03*
X111790Y132259D03*
X152499Y149550D03*
X173499Y149050D03*
X175999Y82428D03*
X97499Y90050D03*
X115876Y125973D03*
Y130050D03*
X174999Y79050D03*
X175499Y86572D03*
X178999Y79050D03*
X176399Y94872D03*
X127999Y157050D03*
X114900Y177900D03*
X154200Y168500D03*
X149400Y166400D03*
X149999Y243504D03*
Y239729D03*
X122397Y252688D03*
X122799Y249150D03*
X147099Y245350D03*
X124999Y246050D03*
X123300Y256000D03*
X157440Y283924D03*
Y303924D03*
Y313924D03*
X141499Y427550D03*
X165500Y416500D03*
X166500Y428500D03*
X153459Y427494D03*
X154101Y445550D03*
X141499Y423050D03*
X159600Y446399D03*
X171722Y513827D03*
X163549Y517100D03*
X150500Y545000D03*
X102100Y514900D03*
X163449Y521650D03*
X107526Y528996D03*
X104502Y530552D03*
X138999Y524213D03*
X173100Y483100D03*
X168453Y527949D03*
X160932Y549468D03*
X135499Y517550D03*
X107499Y497050D03*
X98900Y513400D03*
X172499Y491053D03*
X137899Y545451D03*
X176799Y493850D03*
X150750Y540416D03*
X109400Y543200D03*
X149000Y537500D03*
X106000Y543200D03*
X138416Y553500D03*
X125499Y635550D03*
Y638950D03*
X127999Y645550D03*
X131400Y644600D03*
X144238Y645356D03*
X161000Y639100D03*
X124999Y643050D03*
X129000Y636600D03*
X128600Y640500D03*
X140900Y644000D03*
X134300Y646400D03*
X107000Y604800D03*
X105100Y600000D03*
X157000Y573851D03*
X141300Y565900D03*
X160824Y577000D03*
X144238Y649131D03*
X140400Y649800D03*
X158885Y679436D03*
Y689436D03*
X141500Y711000D03*
X158385Y719436D03*
X111200Y799450D03*
X110195Y809979D03*
X110500Y790200D03*
X110700Y795700D03*
X109831Y806598D03*
X109700Y803200D03*
X110202Y813379D03*
X154799Y838050D03*
X165499Y815550D03*
X110499Y834550D03*
X172660Y815731D03*
X174199Y841050D03*
X159500Y814700D03*
X169106Y815865D03*
X153900Y832200D03*
X98700Y842600D03*
Y822550D03*
X98000Y833500D03*
X163500Y937100D03*
X172500Y919294D03*
X172000Y931600D03*
X106749Y934367D03*
X108441Y924705D03*
X160399Y922850D03*
X153499Y918550D03*
X108845Y931657D03*
X109099Y928250D03*
X171100Y935000D03*
X102100Y968500D03*
X99000Y965000D03*
X172000Y961000D03*
X152500Y960000D03*
X170250Y948500D03*
X154749Y968249D03*
X171000Y939500D03*
X123999Y1054050D03*
Y1050650D03*
X120100Y1053200D03*
X124100Y1047100D03*
X112699Y1058974D03*
X104600Y980500D03*
X154749Y979149D03*
X103200Y985364D03*
X104700Y989900D03*
X120749Y1093990D03*
X164700Y1085400D03*
X105499Y1080550D03*
X106718Y1076050D03*
X137100Y1084800D03*
X140800Y1076300D03*
X121500Y1083600D03*
X121100Y1075300D03*
X116249Y1102550D03*
X112999Y1103740D03*
X117499Y1079300D03*
X157700Y1114948D03*
X157600Y1124948D03*
X159000Y1083000D03*
X127000Y1113500D03*
X123999Y1102550D03*
X138600Y1124600D03*
X116700Y1063500D03*
X105600Y1069500D03*
X108999Y1102050D03*
X137481Y1077557D03*
X137477Y1081177D03*
X124423Y1077523D03*
Y1081177D03*
X127000Y1202000D03*
X148000Y1206000D03*
X106162Y1205702D03*
X114999Y1210363D03*
X130699Y1210653D03*
X118999Y1219050D03*
X123970Y1221573D03*
X101541Y1262607D03*
X116999Y1288050D03*
X101399Y1292550D03*
X107999Y1307713D03*
X120507Y1317050D03*
X143700Y1332500D03*
X101500Y1352000D03*
X113500D03*
X113000Y1341000D03*
X102000D03*
X107228Y1330552D03*
X107500Y1340500D03*
X110499Y1365050D03*
X109999Y1355050D03*
X138000Y1359025D03*
X111499Y1311800D03*
X125999Y1315550D03*
X132999Y1319550D03*
X142667Y1319218D03*
X149562Y1315987D03*
X133475Y1331200D03*
X112440Y1358196D03*
X112999Y1361550D03*
X97229Y1373337D03*
X97000Y1377600D03*
X109228Y1337090D03*
Y1333315D03*
X102700Y1321363D03*
X119499Y1339050D03*
X121000Y1364000D03*
X148024Y1333525D03*
X140000Y1332600D03*
X129000Y1356500D03*
X113500Y1344500D03*
Y1348154D03*
X102350Y1344500D03*
Y1348154D03*
X147400Y1321600D03*
X125100Y1366000D03*
X124290Y1469241D03*
X123808Y1465050D03*
X117390Y1426201D03*
Y1429976D03*
X104935Y1440634D03*
X142999Y1456373D03*
X104999Y1444941D03*
X139815Y1454438D03*
X139235Y1460973D03*
X123999Y1473050D03*
X127898Y1462441D03*
X107300Y1438100D03*
X114499Y1432050D03*
X114000Y1425400D03*
X107999Y1448050D03*
X150338Y1453958D03*
X152499Y1462940D03*
X105099Y1459150D03*
X142900Y1460000D03*
X100800Y1536450D03*
X157440Y1490460D03*
Y1500460D03*
Y1520460D03*
Y1530460D03*
X100499Y1479650D03*
X122199Y1476050D03*
X99899Y1539850D03*
X100000Y1546650D03*
X97499Y1554550D03*
X96999Y1558050D03*
X98144Y1534309D03*
X157400Y1596550D03*
X160200Y1598500D03*
X150999Y1713550D03*
X171999Y1662250D03*
X131999Y1710050D03*
X169100Y1685800D03*
X174250Y1694500D03*
X109499Y1712213D03*
X104999Y1708963D03*
X141500Y1715500D03*
X117249Y1712090D03*
X165575Y1676975D03*
X112753Y1716613D03*
X152633Y1677967D03*
X122642Y1704243D03*
X112562Y1720613D03*
X135499Y1710150D03*
X118499Y1694050D03*
X123749Y1711550D03*
X177900Y1690400D03*
X169600Y1682300D03*
X109499Y1743550D03*
X107300Y1746300D03*
X107100Y1736000D03*
X109399Y1739550D03*
X99199Y1761899D03*
X99999Y1753575D03*
X141999Y1764550D03*
X110099Y1759875D03*
X101399Y1784700D03*
X165900Y1790500D03*
X161900Y1793400D03*
X123393Y1870859D03*
X137999Y1861497D03*
Y1865151D03*
X123592Y1874254D03*
X96600Y1826000D03*
X135999Y1881550D03*
X141300Y1866400D03*
X141800Y1860500D03*
X97999Y1843050D03*
X159421Y1925972D03*
X210638Y62959D03*
X210634Y66863D03*
X201499Y104550D03*
X245499Y100550D03*
X246499Y86050D03*
Y80550D03*
X215138Y72559D03*
X210685Y74725D03*
X210605Y70692D03*
X205938Y72528D03*
X210738Y78459D03*
Y82159D03*
X186999Y99050D03*
X213499Y104650D03*
X223499Y108150D03*
X188999Y120800D03*
X205499Y105550D03*
X225499Y68550D03*
X233749Y110800D03*
X230749Y76300D03*
X207999Y109550D03*
X237899Y107050D03*
X197899Y165075D03*
X218499Y190550D03*
X247800Y269700D03*
X225298Y281114D03*
X213499Y283864D03*
X253871Y291410D03*
X250300Y275100D03*
X250400Y283100D03*
X239600Y278600D03*
X213400Y355300D03*
X224998Y357049D03*
X233998Y357549D03*
X239400Y357400D03*
X252935Y319114D03*
X214063Y318114D03*
X231800Y318414D03*
X179700Y425800D03*
X187699Y492850D03*
X199900Y554050D03*
X182499Y532550D03*
X220000Y516400D03*
X183499Y556100D03*
X188000Y484500D03*
X193549Y575875D03*
X246800Y677100D03*
X216999Y686550D03*
X213999Y725050D03*
X230849Y726050D03*
X252499D03*
X254499Y697700D03*
X249700Y682500D03*
X249800Y689900D03*
X238500Y680800D03*
X228999Y765550D03*
X218224Y765325D03*
X241600Y765700D03*
X236800Y765800D03*
X199000Y815000D03*
X200539Y890300D03*
X211750Y894600D03*
X198924Y975975D03*
X229562Y904113D03*
X215499Y905550D03*
X200799Y896600D03*
X233500Y1066100D03*
X226800Y1093400D03*
X221800Y1069300D03*
X247500Y1085500D03*
X256000Y1133000D03*
X255000Y1125700D03*
X221300Y1083238D03*
X251500Y1136700D03*
X229800Y1073600D03*
X242000Y1066000D03*
X182500Y1275500D03*
X199149Y1362900D03*
X194700Y1385700D03*
X181000Y1365500D03*
X180500Y1369900D03*
X229025Y1471576D03*
X241000Y1469600D03*
X224750Y1483950D03*
X232650Y1493450D03*
X233700Y1481600D03*
X199500Y1627000D03*
X195000Y1645500D03*
X179999Y1655887D03*
X186000Y1644000D03*
X179999Y1644500D03*
X194049Y1792600D03*
X201499Y1781050D03*
X227814Y1887513D03*
X231800Y1887100D03*
X236225Y1883125D03*
X229800Y1875700D03*
X218100Y1886400D03*
X213138Y1952703D03*
X249499Y1928050D03*
X231999Y1914050D03*
X210999Y1942050D03*
X223436Y1890465D03*
X232314Y1890513D03*
X213562Y1926113D03*
X220062Y1931113D03*
X240964Y1934113D03*
X214999Y1909550D03*
X257499Y1911050D03*
X343499Y60150D03*
X296099Y17100D03*
X305099Y17000D03*
X311400Y17100D03*
X317000Y17300D03*
X341499Y63050D03*
Y67110D03*
X343499Y31650D03*
X308999Y87050D03*
X323400Y105200D03*
X291999Y94050D03*
X282800Y87500D03*
X297499Y97550D03*
X315800Y100500D03*
X324800Y89400D03*
X293999Y293550D03*
X326499Y334054D03*
X284999Y338650D03*
X281499Y338550D03*
X313039Y352350D03*
X321900Y364600D03*
X298800Y333000D03*
X294500Y339000D03*
X326499Y337454D03*
X301249Y346050D03*
X344520Y406329D03*
X308999Y716450D03*
X315999Y718950D03*
X279939Y728610D03*
X329499Y801550D03*
X330540Y795509D03*
X327999Y740550D03*
X320499Y798050D03*
X285499Y745050D03*
X282099D03*
X292999Y743650D03*
X298000Y743500D03*
X323249Y749010D03*
X324959Y766750D03*
X277039Y740300D03*
X327749Y744050D03*
X306500Y753550D03*
X340699Y1046086D03*
X283499Y1556050D03*
X279999D03*
X289999Y1554650D03*
X293700Y1553351D03*
X276039Y1551300D03*
X314999Y1527550D03*
X326500Y1550200D03*
X261999Y1516050D03*
X295000Y1513000D03*
X333000Y1578000D03*
X297800Y1561600D03*
X291400Y1561500D03*
X324000Y1562500D03*
X312999Y1566050D03*
X323999Y1577250D03*
X330300Y1561200D03*
X310249Y1569800D03*
X264499Y1964050D03*
X331622Y1944767D03*
X288709Y1948042D03*
X284999Y1947691D03*
X330500Y1966500D03*
X280689Y1942710D03*
X315999Y1958550D03*
X327100Y1966472D03*
X329999Y1952273D03*
X325221Y1927272D03*
X313499Y1919050D03*
X332103Y1948133D03*
X310499Y1957050D03*
X285499Y1930050D03*
X381999Y57050D03*
X398799Y36152D03*
X381999Y50150D03*
X386799Y45000D03*
X381999Y53550D03*
X394199Y45050D03*
X358999Y61550D03*
X354999Y72050D03*
X426000Y93500D03*
X357503Y77043D03*
X374499Y77550D03*
X385999Y78050D03*
X401499Y80550D03*
X371700Y85500D03*
X400499Y406329D03*
X371999Y549300D03*
X394649Y630600D03*
X375999Y698550D03*
X350499Y715050D03*
X371500Y880600D03*
X364499Y1099050D03*
X372999Y1123550D03*
X345499Y1096550D03*
X370149Y1320050D03*
X345424Y1310050D03*
X347324Y1524000D03*
X366149Y1554050D03*
X402499Y1476850D03*
X390999Y1514398D03*
Y1517798D03*
X349774Y1582900D03*
X354500Y1559500D03*
X400999Y1575550D03*
X354000Y1584900D03*
X353499Y1710450D03*
X377900Y1703800D03*
X348499Y1762050D03*
X385499Y1735050D03*
X367000Y1810000D03*
X360000Y1967500D03*
X659549Y1810634D03*
X757499Y745342D03*
X755600Y1149800D03*
X758499Y1371050D03*
X754000Y1551000D03*
X750000Y1560500D03*
X690249Y1805634D03*
X755000Y1825000D03*
X711652Y1822109D03*
X711848Y1825504D03*
X752500Y1954500D03*
X821999Y193116D03*
X827499Y163550D03*
X820749Y163850D03*
X813249Y163800D03*
X839249Y164050D03*
X829917Y216200D03*
X833576Y215432D03*
X837999Y219550D03*
X822100Y279500D03*
X827500Y274500D03*
X770999Y302050D03*
X785499Y291050D03*
X770999Y290050D03*
Y295550D03*
X827499Y313424D03*
X763571Y295622D03*
X777999Y296050D03*
X786978Y298529D03*
X836500Y274950D03*
X812500Y282750D03*
X822100Y261700D03*
X816700Y274300D03*
X791499Y333050D03*
X789999Y336550D03*
X772499Y323050D03*
X758778Y345000D03*
X768178Y333964D03*
X784499Y334050D03*
X772873Y326924D03*
X780499Y330050D03*
X771105Y722789D03*
X829800Y666650D03*
X835150Y677650D03*
X806500Y687250D03*
X781999Y725550D03*
X820600Y664300D03*
X813200Y675900D03*
X788999Y736050D03*
X791999Y733050D03*
X766499Y732842D03*
X762500Y734000D03*
X784939Y733550D03*
X769999Y733050D03*
X792154Y1135926D03*
X825700Y1083100D03*
X771999Y1124550D03*
X767083Y1134550D03*
X764549Y1138500D03*
X784439Y1136550D03*
X814000Y1087000D03*
X772499Y1130050D03*
X789499Y1138050D03*
X779499Y1131050D03*
X825800Y1072300D03*
X815400Y1078800D03*
X803199Y1151850D03*
X822100Y1466800D03*
X774542Y1530050D03*
X804899Y1556950D03*
X827700Y1487600D03*
X836625Y1487400D03*
X771225Y1539474D03*
X767936Y1540336D03*
X784577Y1535628D03*
X812550Y1494050D03*
X774577Y1533796D03*
X791499Y1543550D03*
X793999Y1541050D03*
X784499Y1529050D03*
X814700Y1486300D03*
X788000Y1788000D03*
X774500D03*
X812000Y1799500D03*
X821249Y1791250D03*
X811000Y1793000D03*
X793000Y1803500D03*
X795849Y1805500D03*
X828500Y1877800D03*
X770999Y1820550D03*
X822499Y1815164D03*
X791999Y1819050D03*
X783499Y1827050D03*
X807000Y1822300D03*
X803500Y1822708D03*
X822700Y1871100D03*
X805900Y1887560D03*
X771499Y1936550D03*
X767999Y1945173D03*
X764908Y1946592D03*
X785939Y1946800D03*
X812500Y1898500D03*
X771499Y1940050D03*
X802099Y1961950D03*
X834799Y1946950D03*
X792499Y1949050D03*
X794499Y1941050D03*
X782999Y1937050D03*
X919800Y54600D03*
X924200Y69800D03*
X898800Y96000D03*
X855500Y149500D03*
X873000Y148500D03*
X846500Y149500D03*
X841499Y135550D03*
X861999Y146550D03*
X882499Y147050D03*
X896999Y141550D03*
X916499Y115050D03*
X923761Y85550D03*
X907499Y131800D03*
X902499Y110550D03*
X901499Y92050D03*
X898999Y110550D03*
X897555Y90494D03*
X910999Y124550D03*
X867500Y163924D03*
X867576Y159924D03*
X878078Y240103D03*
Y243878D03*
X854400Y264600D03*
X847878Y250040D03*
X851278Y249974D03*
X842499Y280924D03*
X847500Y246600D03*
X850999Y246550D03*
X874700Y244900D03*
X874900Y238600D03*
X871999Y283924D03*
X886200Y313924D03*
X886600Y303924D03*
X872136Y273924D03*
X858478Y274050D03*
X868799Y294750D03*
X865499Y288050D03*
X867899Y321550D03*
X868299Y336150D03*
X902999Y556050D03*
X878596Y645573D03*
X875100Y644400D03*
X922049Y574375D03*
X879750Y570550D03*
X879950Y565050D03*
X851172Y655432D03*
X878596Y649348D03*
X847772Y655370D03*
X875300Y650500D03*
X851300Y651700D03*
X847600Y651600D03*
X852696Y671197D03*
X922049Y978575D03*
X900499Y962100D03*
X879708Y971892D03*
X878233Y1051095D03*
X877964Y1054485D03*
X850833Y1061441D03*
X847233Y1061492D03*
X847500Y1057800D03*
X851000Y1058000D03*
X874733Y1055792D03*
X874999Y1049550D03*
X883083Y979183D03*
X864499Y1128750D03*
X852333Y1077716D03*
X871499Y1124948D03*
X872086Y1114948D03*
X871999Y1094948D03*
X872086Y1084948D03*
X860133Y1084142D03*
X860799Y1358925D03*
X861849Y1376050D03*
X866700Y1379796D03*
X866596Y1375796D03*
X848888Y1466402D03*
X852288Y1466346D03*
X878054Y1456450D03*
X877853Y1459991D03*
X874100Y1461600D03*
X874900Y1454000D03*
X848861Y1462463D03*
X852500Y1462600D03*
X867523Y1542821D03*
X867199Y1535150D03*
X854327Y1477550D03*
X858827Y1485696D03*
X872086Y1490460D03*
X871999Y1500460D03*
Y1520460D03*
X872086Y1530460D03*
X863699Y1501250D03*
X900500Y1721500D03*
X886439Y1717600D03*
X862800Y1712700D03*
X889800Y1711500D03*
X921549Y1788475D03*
X917499Y1796550D03*
X879700Y1786300D03*
X873300Y1740100D03*
X879664Y1782213D03*
X866914Y1861840D03*
X853499Y1871036D03*
X866914Y1865615D03*
X850099Y1871056D03*
X851500Y1821400D03*
X849375Y1824982D03*
X854905Y1825583D03*
X854480Y1867578D03*
X849999Y1867550D03*
X863700Y1867300D03*
X865300Y1858700D03*
X854814Y1883550D03*
X859314Y1891365D03*
X871921Y1905972D03*
X871421Y1895972D03*
X872086Y1925972D03*
Y1935972D03*
X863699Y1906450D03*
X857099Y1917650D03*
X961499Y100050D03*
X946899Y122550D03*
X932961Y85581D03*
X928461Y75981D03*
X928561Y91481D03*
X928508Y87747D03*
X928428Y83714D03*
X928561Y95181D03*
X928457Y79885D03*
X958999Y96050D03*
X930999Y115550D03*
X937999Y122050D03*
X938499Y115550D03*
X961499Y93350D03*
X926999Y122050D03*
X943499Y82550D03*
X934499Y118750D03*
X926999Y115050D03*
X939549Y175175D03*
X966499Y552050D03*
X965999Y954550D03*
X986400Y1639302D03*
X990425Y1633898D03*
X987029Y1634075D03*
X981200Y1618002D03*
X964000Y1639200D03*
X960900Y1636400D03*
X969600Y1638300D03*
X977500Y1660500D03*
X978000Y1668000D03*
X967600Y1651100D03*
X989502Y1646000D03*
X988800Y1658300D03*
X989000Y1663802D03*
X987200Y1675600D03*
X989900Y1678800D03*
X974000Y1670700D03*
X984211Y1667500D03*
X971558Y1646500D03*
X981500Y1653000D03*
X980800Y1659600D03*
X982050Y1649302D03*
G54D11*
X11999Y53550D03*
X11499Y34050D03*
X10000Y16500D03*
X11499Y142050D03*
X11999Y69050D03*
X6891Y161611D03*
X11302Y161500D03*
X7089Y166111D03*
X11500Y166000D03*
X9499Y301050D03*
Y281550D03*
X8999Y318550D03*
X8599Y751650D03*
X10999Y774050D03*
X8999Y889550D03*
X8499Y979050D03*
X8999Y961550D03*
Y942050D03*
Y926550D03*
X8499Y907050D03*
X8999Y1060550D03*
Y1041050D03*
Y1025550D03*
X8499Y1006050D03*
X8999Y988550D03*
X6500Y1098000D03*
Y1103500D03*
Y1110000D03*
Y1116500D03*
X8499Y1078050D03*
X6500Y1146000D03*
X13000Y1145500D03*
Y1151000D03*
X7000Y1151500D03*
X8799Y1302550D03*
X7499Y1282050D03*
X7999Y1264550D03*
X9399Y1347350D03*
X8299Y1320050D03*
X7099Y1717750D03*
X7199Y1731450D03*
X6099Y1753750D03*
X11299Y1850050D03*
X9099Y1881550D03*
X8499Y1979550D03*
X11500Y1987000D03*
X92999Y52050D03*
X90899Y14850D03*
X23499Y27050D03*
X50999Y21150D03*
Y47750D03*
X27799Y38450D03*
X25799Y64050D03*
X65499Y59050D03*
Y41550D03*
Y27050D03*
X40999Y42050D03*
Y27550D03*
X17600Y5604D03*
X36000D03*
X55700Y5900D03*
X73900Y6200D03*
X90900Y5800D03*
X88000Y36400D03*
X93000Y44900D03*
X92900Y39700D03*
X32400Y115400D03*
X37000Y115300D03*
X32300Y121000D03*
X36900Y120900D03*
X32100Y130700D03*
X37000D03*
X32100Y136600D03*
X36800Y136700D03*
X52499Y145050D03*
Y130550D03*
X59499Y108050D03*
Y90550D03*
Y76050D03*
X96184Y151065D03*
X71015Y123666D03*
X78165Y137116D03*
X95814Y136065D03*
X77165Y110799D03*
X36500Y179000D03*
Y188500D03*
X35000Y198500D03*
X30000Y179000D03*
X23500D03*
X30000Y188500D03*
X24000D03*
X29000Y198000D03*
X23500D03*
X15302Y161500D03*
X19500D03*
X15500Y166000D03*
X19198Y152000D03*
X19698Y166000D03*
X92899Y231450D03*
X48499Y228550D03*
X23999Y229050D03*
X52499Y162550D03*
X96184Y166065D03*
X23895Y238995D03*
X51099Y300050D03*
X90899Y309550D03*
X93199Y279650D03*
X84899Y289250D03*
X86899Y242750D03*
X75299Y261750D03*
X42999Y275650D03*
X48499Y260550D03*
Y243050D03*
X23999Y261050D03*
Y243550D03*
X52199Y342350D03*
X89899Y368350D03*
X94199Y325550D03*
X93499Y337450D03*
X95499Y355450D03*
X89999Y396450D03*
X39999Y359550D03*
Y342050D03*
Y327550D03*
X15499Y360050D03*
Y342550D03*
Y328050D03*
X94500Y456800D03*
X75300Y454100D03*
X67300Y450200D03*
X68899Y445450D03*
X87599Y403950D03*
X76099Y414250D03*
X95399Y416350D03*
X89099Y426150D03*
X93499Y481550D03*
Y477050D03*
X93199Y449850D03*
X93500Y445300D03*
X42299Y564150D03*
X62055Y561550D03*
X49555Y563550D03*
X75999Y556640D03*
X70800Y540300D03*
X77165Y514650D03*
X94499Y486550D03*
X52333Y641295D03*
X72599Y578236D03*
X39999Y576550D03*
X61099Y603236D03*
X93599Y581236D03*
X92599Y606236D03*
X93100Y571640D03*
X44000Y728500D03*
X40000Y729000D03*
X47800Y692800D03*
X53210Y701486D03*
X43499Y657550D03*
X44500Y733000D03*
X40000D03*
X43999Y737550D03*
X39999Y738050D03*
X44499Y742050D03*
X39999D03*
X39899Y754850D03*
X39399Y768750D03*
X27199Y764950D03*
X28599Y775450D03*
X26399Y750850D03*
X14799Y751450D03*
X17299Y773950D03*
X79900Y791300D03*
X67999Y790400D03*
X53999Y791000D03*
X93299Y862050D03*
X26799Y874550D03*
X26099Y891650D03*
X76399Y820450D03*
X70100Y818900D03*
X93690Y887139D03*
X93900Y882400D03*
X94001Y856895D03*
X93808Y852063D03*
X93499Y892050D03*
X25699Y916150D03*
X25099Y942150D03*
X23899Y957950D03*
X93499Y897152D03*
X93000Y907165D03*
X77499Y921550D03*
X77002Y952079D03*
X76711Y948089D03*
X77499Y962152D03*
X83988Y934028D03*
X24799Y992250D03*
X33899Y1005950D03*
X65799Y994050D03*
X72799Y982950D03*
X86900Y981600D03*
X67000Y1011500D03*
X21500Y1122500D03*
Y1092500D03*
X17500D03*
X22500Y1183000D03*
Y1176500D03*
Y1170000D03*
Y1164500D03*
X18000Y1145500D03*
X17500Y1150500D03*
X22447Y1223247D03*
X23200Y1209300D03*
X21299Y1300250D03*
X21799Y1282750D03*
X22321Y1231121D03*
X18099Y1343550D03*
X96000Y1369000D03*
X96100Y1384650D03*
X77166Y1353400D03*
X93316Y1351000D03*
X77165Y1327335D03*
X76499Y1507050D03*
Y1498050D03*
Y1512050D03*
Y1503050D03*
X76999Y1528050D03*
Y1519050D03*
X83499Y1602050D03*
X92499Y1589050D03*
X86999D03*
X83499Y1594050D03*
Y1598050D03*
X74999Y1602050D03*
X78999D03*
X81499Y1589050D03*
X78999Y1593550D03*
X74999Y1598050D03*
Y1593550D03*
X78999Y1598050D03*
X90999Y1628550D03*
Y1624550D03*
X91121Y1632549D03*
X86299Y1632550D03*
X85999Y1628550D03*
Y1624550D03*
X15299Y1723450D03*
X15399Y1708350D03*
X14899Y1736250D03*
X15299Y1753250D03*
X84099Y1737150D03*
X83599Y1744750D03*
X77165Y1759550D03*
X93499D03*
X94336Y1773113D03*
X78529Y1788113D03*
X38600Y1880200D03*
X31400Y1885200D03*
X30400Y1849650D03*
X23999Y1857950D03*
X27199Y1874350D03*
X52999Y1871550D03*
X57499Y1871050D03*
X36100Y1892200D03*
X58999Y1958050D03*
X82499Y1957050D03*
X73499D03*
X66499D03*
X92499Y1959050D03*
X47499Y1915050D03*
X62999Y1914550D03*
Y1926050D03*
X81499Y1915550D03*
X47499Y1930550D03*
X62499Y1939550D03*
X73499Y1945550D03*
X83999Y1945050D03*
X79500Y1987500D03*
X61500D03*
X44500Y1987000D03*
X26500D03*
X55999Y1982550D03*
X96999Y49550D03*
X157299Y5150D03*
X107000Y6000D03*
X97800Y36000D03*
X96900Y40400D03*
X167499Y43550D03*
X116400Y56000D03*
X129100Y55900D03*
X127499Y65050D03*
X141999Y65550D03*
X156499Y66050D03*
X169300Y130300D03*
X178700Y129900D03*
X152999Y141050D03*
X123499Y149050D03*
X133999D03*
X142999Y141050D03*
X132999Y141550D03*
X176499Y140050D03*
X167499Y149550D03*
X144499Y149050D03*
X163499Y140050D03*
X160999Y149550D03*
X123499Y140050D03*
X114800Y68500D03*
X177899Y199250D03*
X117500Y162300D03*
X124300Y167800D03*
X131799Y201950D03*
X142688Y218861D03*
X143110Y203861D03*
X97999Y199050D03*
X135399Y277050D03*
X130799Y300250D03*
X158999Y259800D03*
X152808Y246341D03*
X166800Y240800D03*
X133000Y240500D03*
X157740Y273924D03*
X139399Y372350D03*
X167299Y369350D03*
X130099Y326150D03*
X134699Y356050D03*
X126099Y396150D03*
X152499Y395950D03*
X135999Y472550D03*
X135140Y478930D03*
X100500Y456700D03*
X99399Y437450D03*
X124899Y409050D03*
X133499Y445050D03*
X128999Y445550D03*
X130000Y452000D03*
X97699Y477050D03*
Y481550D03*
X149700Y471600D03*
X154100Y476500D03*
X164600Y476700D03*
X171300D03*
X97999Y445550D03*
X97699Y449850D03*
X108599Y557236D03*
X154099Y529236D03*
X101500Y536500D03*
X139200Y484300D03*
X134499Y488050D03*
X145649Y509550D03*
X136349Y509050D03*
X98999Y488050D03*
X140499Y499050D03*
X153499Y502550D03*
X148999D03*
X136299Y499050D03*
X108900Y587600D03*
X162500Y623400D03*
X140000Y587700D03*
X140499Y600550D03*
X152400Y643300D03*
X140499Y626050D03*
X143999Y605550D03*
X170799Y689150D03*
X171999Y672450D03*
X131099Y700450D03*
X139099Y707150D03*
X152124Y651868D03*
X159054Y665400D03*
X110800Y772700D03*
X178899Y765250D03*
X172599Y774250D03*
X156499Y876050D03*
Y870550D03*
X97499Y862050D03*
X111299Y821050D03*
X172099Y877450D03*
X168499Y846713D03*
X173899Y846550D03*
X161999Y843550D03*
Y848050D03*
X156499Y846050D03*
X156999Y850050D03*
X158114Y883290D03*
X156499Y886950D03*
X155499Y891050D03*
Y896050D03*
X97700Y887400D03*
X97900Y882400D03*
X163999Y863050D03*
X159999D03*
X155999Y859050D03*
Y863050D03*
X97800Y851800D03*
X98001Y856950D03*
X97499Y892550D03*
X109500Y901100D03*
X153299Y943750D03*
X106500Y943000D03*
X105300Y960300D03*
X169299Y956350D03*
X159459Y896616D03*
X163499Y896550D03*
X157499Y909050D03*
Y904550D03*
X171499Y998650D03*
X156499Y985950D03*
X149499Y997650D03*
X162499Y1023550D03*
X163499Y1035050D03*
X158300Y1015000D03*
X141234Y1029885D03*
X140864Y1044885D03*
X159499Y1044579D03*
X165600Y1057428D03*
X110999Y1130550D03*
X115200Y1130300D03*
X110999Y1126050D03*
Y1122050D03*
Y1118050D03*
X114999Y1126050D03*
Y1122050D03*
Y1118050D03*
X137900Y1103400D03*
X139100Y1097100D03*
X169299Y1067150D03*
X168099Y1083550D03*
X167999Y1092850D03*
X143200Y1116300D03*
X134500Y1108100D03*
X171599Y1139950D03*
X167499Y1118550D03*
X167999Y1130550D03*
X133200Y1132100D03*
X164999Y1075550D03*
X159055Y1070400D03*
X106999Y1114960D03*
X144149Y1226113D03*
Y1222113D03*
X148499D03*
Y1226113D03*
X145900Y1163200D03*
X163499Y1171650D03*
X151699Y1158550D03*
X144399Y1171150D03*
X150999Y1181150D03*
X141499Y1185550D03*
X151499Y1173050D03*
X121657Y1224604D03*
X120999Y1188050D03*
X111999D03*
X102999D03*
X128400Y1188600D03*
X144149Y1230113D03*
X148486D03*
X104999Y1231050D03*
X100999Y1231032D03*
X120999Y1228550D03*
X120499Y1264550D03*
X126499D03*
X123938Y1267623D03*
X103499Y1305050D03*
X117149Y1267550D03*
X145999Y1353050D03*
X167499Y1389050D03*
X123500Y1360300D03*
X156999Y1397750D03*
X143199Y1412050D03*
X163499Y1433350D03*
X166799Y1409350D03*
X178200Y1393400D03*
X176599Y1447450D03*
X172299Y1465850D03*
X165499Y1453550D03*
X157915Y1420460D03*
X140799Y1435460D03*
X166799Y1487450D03*
X176299Y1500150D03*
X159054Y1476200D03*
X124999Y1616050D03*
Y1620050D03*
Y1629050D03*
Y1633050D03*
X119999Y1629050D03*
X120100Y1633100D03*
X122499Y1668550D03*
Y1672550D03*
X126562Y1670613D03*
X118999Y1670550D03*
X157500Y1797400D03*
X126599Y1789650D03*
X120299Y1796150D03*
X142144Y1801644D03*
X104417Y1791480D03*
X144499Y1745550D03*
X137999Y1747723D03*
X129999Y1747050D03*
X123499D03*
X117499Y1745050D03*
X97999Y1815050D03*
X104500Y1813400D03*
X173899Y1813250D03*
X177599Y1866750D03*
X168299Y1879850D03*
X168499Y1855550D03*
X127499Y1889050D03*
X126999Y1882550D03*
X111499Y1877550D03*
Y1882550D03*
X122999Y1883050D03*
X115999Y1882550D03*
X157999Y1840972D03*
X158000Y1825400D03*
X159054Y1881800D03*
X167200Y1868000D03*
X159054Y1855050D03*
X143491Y1856400D03*
X116499Y1877550D03*
X122999Y1889050D03*
X132700Y1972400D03*
X137900Y1972200D03*
X126500Y1972400D03*
X168899Y1960750D03*
X163599Y1892050D03*
X159173Y1935972D03*
X142499Y1905972D03*
X141499Y1895972D03*
X132700Y1978600D03*
X137900Y1978400D03*
X126600Y1978500D03*
X119999Y1978550D03*
X119499Y1972550D03*
X98000Y1987500D03*
X163500D03*
X146000D03*
X128500D03*
X115000Y1987000D03*
X189499Y39150D03*
X197999Y39900D03*
X193999D03*
X208499Y45650D03*
X199999Y46050D03*
X194499Y44050D03*
X246200Y65800D03*
X246000Y61300D03*
Y56500D03*
Y52100D03*
X245600Y43800D03*
X245500Y39100D03*
X247100Y47900D03*
X189499Y4550D03*
X206999Y5050D03*
X226499D03*
X241999D03*
X261499Y4550D03*
X225499Y52550D03*
Y46550D03*
Y63550D03*
Y58050D03*
X183499Y45550D03*
X192499Y57550D03*
X246000Y70800D03*
X244900Y149100D03*
X244499Y136550D03*
Y122050D03*
X229099Y161350D03*
X206899Y171650D03*
X190199Y178650D03*
X232400Y220700D03*
X210999Y221550D03*
X191999D03*
X249800Y248800D03*
X235399Y263350D03*
X201199Y266750D03*
X181299Y267350D03*
X217999Y250550D03*
X203499D03*
X185999D03*
X187199Y359050D03*
X223799Y365350D03*
X209199Y365050D03*
X181599Y396250D03*
X217599Y396450D03*
X258999Y396650D03*
X179999Y442550D03*
X179649Y438550D03*
X183999D03*
Y442550D03*
Y447050D03*
X179999D03*
X209999Y426150D03*
X237699Y426050D03*
X218499Y474850D03*
X251499Y446050D03*
X231999Y445550D03*
X251999Y462050D03*
X232499Y461550D03*
X209499Y412550D03*
X220000Y421000D03*
X232999Y414550D03*
X252499Y415050D03*
X194999Y490050D03*
X190499Y487550D03*
X191199Y491550D03*
X244199Y483350D03*
X224299Y494650D03*
X242099Y511750D03*
X244999Y559550D03*
Y545050D03*
X220499Y560050D03*
Y545550D03*
X257499Y530050D03*
Y512550D03*
Y498050D03*
X205300Y508100D03*
X190499Y507513D03*
X257199Y640050D03*
X224999Y613450D03*
X256499Y609050D03*
Y591550D03*
Y577050D03*
X245000Y647000D03*
X244499Y632050D03*
X219999Y647050D03*
Y632550D03*
X207300Y639400D03*
X206499Y623550D03*
Y609050D03*
X181999Y641550D03*
Y624050D03*
Y609550D03*
X244999Y577050D03*
X220499Y577550D03*
X199199Y659150D03*
X234200Y668300D03*
X226399Y677550D03*
X212999Y677350D03*
X190399Y689050D03*
X182599Y688350D03*
X246500Y663300D03*
X218800Y668700D03*
X224099Y770250D03*
X209500Y759000D03*
X208799Y766750D03*
X214799Y774750D03*
X245599Y773450D03*
X234299Y773750D03*
X247099Y795050D03*
X227199D03*
X197099D03*
X254699Y807650D03*
X233799Y806350D03*
X208299Y805350D03*
X198199Y805950D03*
X190699Y778350D03*
X215999Y887550D03*
X220499D03*
X215499Y883550D03*
X204496Y846111D03*
X204649Y838050D03*
X208999D03*
X209000Y846113D03*
X204649Y842113D03*
X208986D03*
X244099Y857450D03*
X245199Y878050D03*
X232399Y886550D03*
X252899Y886350D03*
X252399Y838250D03*
X245399Y823550D03*
X217300Y816800D03*
X198499Y884113D03*
X245399Y907450D03*
X243899Y923650D03*
X242199Y938750D03*
X256199Y916250D03*
X254899Y929250D03*
X253499Y938050D03*
X252499Y948850D03*
X244199Y973250D03*
X225299Y957650D03*
X213999Y958650D03*
X206699Y953050D03*
X203999Y943350D03*
X204699Y929450D03*
X205999Y978250D03*
X256499Y967050D03*
X233499Y966050D03*
X216999Y967550D03*
X254499Y984550D03*
X245899Y995250D03*
X232299Y981950D03*
X206299Y990250D03*
X207299Y1008150D03*
X202100Y1028100D03*
X253999Y1052050D03*
X253499Y1038550D03*
X232499Y1038050D03*
X216499Y1053050D03*
X215999Y1039550D03*
X258999Y1011550D03*
X233999Y1012550D03*
Y997050D03*
X217999Y1012050D03*
X217499Y998550D03*
Y981050D03*
X199499Y1093850D03*
X209900Y1093600D03*
X249499Y1104150D03*
X260349Y1139200D03*
X214499Y1154250D03*
X223099Y1182750D03*
X210199Y1173450D03*
X204199Y1163850D03*
X208199Y1145850D03*
X180400Y1202800D03*
X201600Y1205900D03*
X220999Y1224350D03*
X242199Y1210050D03*
X242599Y1198350D03*
X232599Y1195750D03*
X247899Y1208650D03*
X251999Y1184550D03*
X212499Y1212550D03*
X181700Y1219900D03*
X212499Y1184550D03*
X196499Y1224550D03*
Y1215550D03*
Y1196550D03*
X202199Y1276850D03*
X202899Y1291450D03*
X179500Y1262000D03*
X179800Y1244100D03*
X196399Y1236650D03*
X221599Y1237250D03*
X222299Y1251850D03*
X229899Y1250550D03*
X216300Y1274800D03*
X234299Y1232650D03*
X261199Y1227950D03*
X250900Y1248500D03*
X242900Y1263000D03*
X232799Y1276150D03*
X254899Y1289950D03*
X241399Y1303250D03*
X211499Y1267050D03*
Y1258050D03*
Y1239050D03*
X195499Y1279050D03*
Y1270050D03*
Y1251050D03*
X239099Y1314150D03*
X252399Y1326350D03*
X219099Y1325950D03*
X226599Y1340250D03*
X207699Y1337950D03*
X195500Y1352500D03*
X213199Y1350050D03*
X227399Y1363050D03*
X234300Y1375700D03*
X217499Y1387450D03*
X249800Y1388400D03*
X245999Y1358050D03*
X246499Y1370050D03*
X245999Y1339050D03*
X208049Y1385550D03*
X258999Y1396950D03*
X230599Y1400250D03*
X217999Y1408850D03*
X204699Y1418350D03*
X203199Y1393250D03*
X201000Y1408500D03*
X180599Y1424050D03*
X180000Y1439500D03*
X204999Y1472650D03*
X250199Y1473550D03*
X226300Y1447800D03*
X230899Y1437350D03*
X238899Y1453750D03*
X259299Y1438750D03*
X227999Y1421550D03*
X212400Y1433700D03*
X194200Y1457900D03*
X244999Y1412550D03*
X245499Y1424550D03*
X181500Y1479000D03*
X202399Y1500750D03*
X208999Y1491250D03*
X247500Y1499000D03*
X248000Y1482000D03*
X212899Y1535550D03*
X230999D03*
X213399Y1500300D03*
X236999Y1535550D03*
X180299Y1626550D03*
X180000Y1619600D03*
X195700Y1619100D03*
X195600Y1623700D03*
X180299Y1634550D03*
X179733Y1630590D03*
X246200Y1617600D03*
X239400Y1624300D03*
X218000Y1614300D03*
X209200Y1624000D03*
X228999Y1637550D03*
X211999Y1568550D03*
X238300Y1575100D03*
X231499Y1575050D03*
X224499D03*
X217999Y1574550D03*
X211999D03*
X258700Y1645100D03*
X237400Y1663800D03*
X230600Y1670500D03*
X197600Y1694900D03*
X204400Y1688200D03*
X216601Y1684350D03*
X226800Y1684200D03*
X220100Y1691700D03*
X209901Y1691850D03*
X212000Y1701300D03*
X201801Y1701450D03*
X195001Y1708150D03*
X205200Y1708000D03*
X180701Y1716050D03*
X195500Y1717000D03*
X200600Y1663600D03*
X199900Y1670600D03*
X213000Y1672500D03*
X181900Y1675300D03*
X255699Y1722550D03*
X222700Y1710100D03*
X242999Y1658050D03*
X193499Y1674050D03*
X253999Y1676550D03*
X235499Y1697050D03*
X256499Y1710050D03*
X180000Y1731000D03*
X179701Y1724550D03*
X195000Y1725500D03*
X249199Y1743150D03*
X222499Y1743850D03*
X259499Y1760650D03*
X221499Y1760950D03*
X199699Y1761450D03*
X220799Y1791550D03*
X252199Y1793050D03*
X238699Y1801850D03*
X205199Y1801950D03*
X182299Y1801350D03*
X206900Y1726700D03*
X185999Y1746050D03*
X237999Y1730550D03*
X244999Y1755050D03*
X253899Y1813250D03*
X215299Y1813950D03*
X255999Y1855950D03*
X204399Y1855450D03*
X206999Y1867550D03*
X241199Y1867150D03*
X244700Y1878700D03*
X224800Y1867000D03*
X212399Y1885850D03*
X199599Y1879850D03*
X181099Y1885850D03*
X261499Y1825050D03*
X209999D03*
X192100Y1813500D03*
X228999Y1856050D03*
X241255Y1896055D03*
X205499Y1968650D03*
X183999Y1968150D03*
X190399Y1961250D03*
X207199Y1892850D03*
X191599Y1891550D03*
X238999Y1970550D03*
X232999Y1971050D03*
X227499D03*
X221300Y1971200D03*
X240900Y1979000D03*
X225199Y1978750D03*
X209699D03*
X188199Y1978250D03*
X254500Y1987500D03*
X236500D03*
X216999Y1987550D03*
X199000Y1987500D03*
X183000D03*
X199600Y1974900D03*
X289499Y39050D03*
X286603Y34928D03*
X278999Y5050D03*
X292999Y4550D03*
X310499Y5050D03*
X329999D03*
X306999Y55450D03*
X311299D03*
X315799Y55350D03*
X290999Y67550D03*
X300700Y39400D03*
X304500Y44500D03*
X305100Y39700D03*
X294100Y28000D03*
X308900Y41000D03*
X308800Y46400D03*
X306100Y126500D03*
X332200Y94200D03*
X283599Y106250D03*
X274700Y131500D03*
X280999Y120050D03*
X289999Y72550D03*
X288499Y76550D03*
X289499Y80550D03*
X308499Y72550D03*
X303999Y74050D03*
X307999Y78550D03*
X343799Y204550D03*
X321799Y173950D03*
X343399Y161350D03*
X307199Y205550D03*
X317499Y192950D03*
X331499Y193250D03*
X262699Y208550D03*
X262299Y164050D03*
X280999Y152050D03*
X343999Y190050D03*
X337999Y219050D03*
X310499Y216550D03*
X290999Y216050D03*
X271999D03*
X325499Y249450D03*
X313199Y270350D03*
X297999Y245050D03*
X283499D03*
X265999D03*
X343499Y253550D03*
X337499Y282550D03*
X313000Y313900D03*
X316999Y312576D03*
X305998Y352114D03*
X293998Y361114D03*
Y356614D03*
Y352114D03*
X289998Y361114D03*
Y356614D03*
Y352114D03*
X276299Y376050D03*
X299899Y376650D03*
X328799Y372350D03*
X339399Y358050D03*
X289399Y395750D03*
X310999Y396250D03*
X338399Y395650D03*
X321748Y343299D03*
X277799Y338599D03*
X266699Y425050D03*
X336099Y417550D03*
X322099Y426850D03*
X338899Y433850D03*
X300899Y431850D03*
X328599Y442250D03*
X291599Y446150D03*
X266199Y472350D03*
X327900Y463200D03*
X306100Y462000D03*
X286999Y462050D03*
X272499Y445050D03*
X272999Y461050D03*
X269999Y415050D03*
X284499D03*
X303999Y415550D03*
X324999Y414550D03*
X277999Y545350D03*
X329999Y510450D03*
X298599Y501250D03*
X309399Y513450D03*
X321999Y533150D03*
X297599Y519350D03*
X340799Y512050D03*
X341399Y535850D03*
Y558950D03*
X331999Y555050D03*
Y540550D03*
X307499Y555550D03*
Y541050D03*
X281999Y529550D03*
Y512050D03*
Y497550D03*
X321999Y550550D03*
X297499Y551050D03*
X333499Y483050D03*
X312499Y484050D03*
X292999Y483550D03*
X321299Y565250D03*
X296199Y568550D03*
X320799Y582050D03*
X340299Y586550D03*
X342199Y613050D03*
X328599Y602450D03*
X302899Y607950D03*
X328499Y635650D03*
X317999Y627850D03*
X342099Y646350D03*
X280999Y608550D03*
Y591050D03*
Y576550D03*
X331999Y572550D03*
X307499Y573050D03*
X331999Y646550D03*
X307499Y647050D03*
X293999Y630550D03*
Y616050D03*
X269499Y631050D03*
Y616550D03*
X341899Y664950D03*
X342599Y678850D03*
X341399Y715050D03*
X330799Y712450D03*
X324599Y696150D03*
X297699Y681850D03*
X296399Y716950D03*
X308899Y705150D03*
X298399Y703450D03*
X331999Y678550D03*
Y661050D03*
X307499Y679050D03*
Y661550D03*
X293999Y648050D03*
X269499Y648550D03*
X294999Y767050D03*
X290999D03*
X294999Y762550D03*
Y758050D03*
X290999Y762550D03*
Y758050D03*
X306999D03*
X338099Y811650D03*
X307999Y803150D03*
X307899Y794550D03*
X287799Y794850D03*
X268099Y795450D03*
X275299Y806350D03*
X315000Y754500D03*
X338599Y821650D03*
X318999Y814350D03*
X338599Y840450D03*
X325599Y823950D03*
X283599Y857450D03*
X293899Y843850D03*
X304899Y856150D03*
X315199Y869450D03*
X323099Y885050D03*
X340099Y887350D03*
X330299Y871850D03*
X323799Y859850D03*
X313499Y847850D03*
X300199Y835250D03*
X288899Y820550D03*
X264999Y858450D03*
X280999Y843050D03*
Y827550D03*
X264999Y842550D03*
X264499Y829050D03*
X297499Y884050D03*
Y868550D03*
X281499Y883550D03*
X280999Y870050D03*
X265799Y901850D03*
X274299Y912950D03*
X310699Y943550D03*
X323499Y956950D03*
X329799Y970650D03*
X331099Y923650D03*
X322099Y913650D03*
X302499Y899050D03*
X321099Y899650D03*
X338399Y901050D03*
X340099Y910350D03*
X340399Y931250D03*
X340099Y952850D03*
X328099Y937250D03*
X315199Y925950D03*
X302199Y914650D03*
X287299Y901050D03*
X269599Y923950D03*
X267199Y935350D03*
X264799Y946850D03*
X263299Y959350D03*
X281099Y943550D03*
X278799Y956150D03*
X277599Y975250D03*
X290099Y948650D03*
X289399Y963350D03*
X288099Y971250D03*
X299399Y965950D03*
X298099Y977250D03*
X307999Y970650D03*
X272999Y965550D03*
X333099Y983450D03*
X285399Y982950D03*
X294699Y989550D03*
X306699Y981250D03*
X304399Y997550D03*
X320999Y997250D03*
X331299Y1017150D03*
X331599Y1028750D03*
X329599Y1040750D03*
X321299Y1012450D03*
Y1024750D03*
X318299Y1038750D03*
X329599Y1057050D03*
X317699Y1054650D03*
X299999Y1052350D03*
X289699Y1021750D03*
X298399Y1008150D03*
X287099Y1000150D03*
X306399Y1020750D03*
X303699Y1038050D03*
X304699Y1057050D03*
X287099Y1035050D03*
X275099Y1024750D03*
X262499Y995850D03*
X269999Y1052550D03*
Y1037050D03*
X274999Y1012050D03*
Y996550D03*
X272999Y981050D03*
X339599Y1081550D03*
X319999Y1066950D03*
X274900Y1115600D03*
X262499Y1129150D03*
X272999Y1102850D03*
X312299Y1093550D03*
X276299Y1134550D03*
X290699Y1122650D03*
X329299Y1098550D03*
X326599Y1112350D03*
X307999Y1142050D03*
X299499Y1113550D03*
Y1098050D03*
X283499Y1113050D03*
X282999Y1099550D03*
X332999Y1138550D03*
Y1123050D03*
X317999Y1137550D03*
X316499Y1124550D03*
X283299Y1144850D03*
X323999Y1153250D03*
X304499Y1156650D03*
X313499Y1170150D03*
X291399Y1174150D03*
X300699Y1185150D03*
X279799Y1191750D03*
X286599Y1203750D03*
X315408Y1202663D03*
X329799Y1182750D03*
X311999Y1213850D03*
X300699Y1227350D03*
X272999Y1214150D03*
X326649Y1218850D03*
X328999Y1200550D03*
X333349Y1307000D03*
X310299Y1240050D03*
X264800Y1261300D03*
X283799Y1249250D03*
X304699Y1265850D03*
X312499Y1280350D03*
X300499Y1305350D03*
X274299Y1276450D03*
X295399Y1292950D03*
X281099Y1302850D03*
X333349Y1288900D03*
Y1270500D03*
X327999Y1255050D03*
X326649Y1227850D03*
X333349Y1332800D03*
X311500Y1316300D03*
X264799Y1313850D03*
X286799Y1326450D03*
X297899Y1336150D03*
X298099Y1357250D03*
X265299Y1339650D03*
X263699Y1359550D03*
X301699Y1377950D03*
X278799Y1386250D03*
X265499Y1376950D03*
X343599Y1360050D03*
X344399Y1338150D03*
X313600Y1391300D03*
X312900Y1366900D03*
X333349Y1363500D03*
X311900Y1344900D03*
X286499Y1364050D03*
Y1345050D03*
X301699Y1395750D03*
X268499Y1453550D03*
X278000Y1422000D03*
X270599Y1408550D03*
X303499Y1411250D03*
X300899Y1433350D03*
X286600Y1449700D03*
X304699Y1457550D03*
X344099Y1449550D03*
Y1421150D03*
Y1393750D03*
X313600Y1442700D03*
X312800Y1467400D03*
X333349Y1429500D03*
X312100Y1420700D03*
X285499Y1418550D03*
Y1427550D03*
Y1399550D03*
X333349Y1393100D03*
Y1481900D03*
X332500Y1519700D03*
X296599Y1497150D03*
X312000Y1514600D03*
X286700Y1516100D03*
X305998Y1569114D03*
X293998Y1578114D03*
Y1573614D03*
Y1569114D03*
X289998Y1578114D03*
Y1573614D03*
Y1569114D03*
X307000Y1619600D03*
X344500Y1583600D03*
X337199Y1636350D03*
X278499Y1621550D03*
X265700Y1635100D03*
X289000Y1641800D03*
X320299Y1642950D03*
X316799Y1657450D03*
X302399Y1662950D03*
X284300Y1676900D03*
X334399Y1691650D03*
X329999Y1716950D03*
X291099Y1707450D03*
X335767Y1662735D03*
X318499Y1675550D03*
X299999Y1696050D03*
X270999Y1660550D03*
X273499Y1694050D03*
X280499Y1718550D03*
X320999Y1706050D03*
X303999Y1722050D03*
X343899Y1752650D03*
X297099Y1733850D03*
X270599Y1748950D03*
X290699Y1760750D03*
X286599Y1791850D03*
X327299D03*
X322299Y1802150D03*
X303999Y1800850D03*
X270599Y1801450D03*
X263499Y1734550D03*
X285499Y1742550D03*
X321999Y1733050D03*
X303499Y1753550D03*
X321499Y1772550D03*
X315499Y1812250D03*
X284299Y1811150D03*
X270299Y1867250D03*
X337499Y1855950D03*
X316999D03*
X298999D03*
X308099Y1880550D03*
X295299Y1870250D03*
X313599Y1889250D03*
Y1870250D03*
X326399Y1876250D03*
X336799Y1888950D03*
Y1869950D03*
X283999Y1856050D03*
X306000Y1961500D03*
X305500Y1965500D03*
X293999Y1971050D03*
Y1966550D03*
Y1962050D03*
X289499Y1961550D03*
Y1966550D03*
Y1971050D03*
X314099Y1901250D03*
X326899Y1907250D03*
X326399Y1895250D03*
X335799Y1916450D03*
X336799Y1897950D03*
X305999Y1913050D03*
X302499Y1922050D03*
X296858Y1956228D03*
X326799Y1977050D03*
X329999Y1987550D03*
X311500Y1987500D03*
X291499Y1987550D03*
X272000Y1987500D03*
X371999Y15550D03*
X376499D03*
X380999D03*
X369999Y23550D03*
Y19050D03*
X382499Y20050D03*
X416999Y25050D03*
X417499Y46550D03*
X416999Y63550D03*
X345499Y5050D03*
X364999Y4550D03*
X382499Y5050D03*
X395999Y5550D03*
X413499Y6050D03*
X381299Y136750D03*
X389599Y90950D03*
X400499Y134050D03*
Y119550D03*
X363999Y136050D03*
X417499Y79050D03*
Y93550D03*
Y108050D03*
Y125550D03*
X416999Y145050D03*
X360999Y113050D03*
X356499D03*
X351999D03*
X347499D03*
X360999Y100550D03*
X355999D03*
X350999D03*
X345999D03*
X387599Y220150D03*
X385999Y207250D03*
X354099Y175350D03*
X389299Y161650D03*
X400499Y151550D03*
X363999Y153550D03*
X369999Y219050D03*
X382499Y190550D03*
X355499Y219050D03*
X362999Y190050D03*
X416999Y164050D03*
X417999Y185050D03*
X423799Y259750D03*
X383299Y310250D03*
X386899Y299250D03*
X359399Y307250D03*
X347399Y301950D03*
X355999Y242750D03*
X347699Y269050D03*
X382999Y276650D03*
X412999Y307550D03*
Y290050D03*
Y275550D03*
X369499Y282550D03*
X381999Y254050D03*
X354999Y282550D03*
X362499Y253550D03*
X354099Y373050D03*
X368299Y386350D03*
X357999Y359050D03*
X380599Y381050D03*
X386599Y348450D03*
X394899Y357750D03*
X422499Y348150D03*
X422199Y363350D03*
X420199Y391350D03*
X419599Y458550D03*
X426599Y415350D03*
X415099Y422550D03*
X410799Y431150D03*
X354699Y426650D03*
X356399Y451750D03*
X351399Y470750D03*
X358399Y498650D03*
X357399Y521250D03*
Y530550D03*
Y543850D03*
X357999Y559450D03*
X415999Y518550D03*
X420199Y638550D03*
X427499Y624550D03*
X359399Y576050D03*
Y599650D03*
X360399Y615550D03*
X359699Y627550D03*
X345399Y698950D03*
X358899Y657150D03*
X359399Y669450D03*
X359199Y690650D03*
X357699Y707750D03*
X353999Y787750D03*
X347699Y773450D03*
X355999Y752850D03*
X424999Y766550D03*
X422999Y785050D03*
Y799550D03*
X418799Y896050D03*
Y877050D03*
X422499Y855550D03*
Y836550D03*
X422999Y817050D03*
X374500Y973500D03*
X375000Y939000D03*
Y1034000D03*
X424299Y1034050D03*
X423299Y1013050D03*
Y994050D03*
X373500Y1089500D03*
X419999Y1115550D03*
X409499Y1102550D03*
X416099Y1183550D03*
X415499Y1176050D03*
Y1161550D03*
X419499Y1219550D03*
X377499Y1210050D03*
Y1201050D03*
Y1182050D03*
X420099Y1241550D03*
X419499Y1234050D03*
X376599Y1293950D03*
X376499Y1264550D03*
Y1255550D03*
Y1236550D03*
X424999Y1278550D03*
X425499Y1290550D03*
X424999Y1259550D03*
X416699Y1342650D03*
X416199Y1367550D03*
X375599Y1323350D03*
X374499Y1375550D03*
Y1366550D03*
Y1347550D03*
X423299Y1430350D03*
X426799Y1416050D03*
X422299Y1394950D03*
X425799Y1447950D03*
X427099Y1469150D03*
X376299Y1437650D03*
X373099Y1456550D03*
X373499Y1430050D03*
Y1421050D03*
Y1402050D03*
X414799Y1532350D03*
X424299Y1541350D03*
X374099Y1554550D03*
X374799Y1491250D03*
X415999Y1603250D03*
X416199Y1625250D03*
X425499Y1635050D03*
X418299Y1561250D03*
X351899Y1570850D03*
X350600Y1610900D03*
X349099Y1634550D03*
X376099Y1572850D03*
X375099Y1608250D03*
X377700Y1629000D03*
X414799Y1653750D03*
X414399Y1678350D03*
X414499Y1707250D03*
X374999Y1656750D03*
X377099Y1696350D03*
X380099Y1709650D03*
X351099Y1691150D03*
X352000Y1700400D03*
X427499Y1662050D03*
X417799Y1790850D03*
X387899Y1802850D03*
X359499Y1736850D03*
X376799Y1734050D03*
X393499Y1759550D03*
X376499Y1775550D03*
X357999Y1796050D03*
X410757Y1772872D03*
X393999Y1784550D03*
X422999Y1778550D03*
X414499Y1810450D03*
X355699Y1810750D03*
X426499Y1855450D03*
X406999Y1855950D03*
X391499D03*
X369499D03*
X351999Y1855450D03*
X359999Y1878550D03*
X421399Y1888050D03*
X369799Y1880050D03*
X389499Y1885050D03*
X348999Y1879050D03*
X406499Y1874050D03*
X367299Y1956950D03*
X358999Y1925050D03*
X359999Y1897550D03*
Y1906550D03*
X420399Y1962550D03*
Y1934550D03*
Y1953550D03*
X421399Y1916050D03*
Y1907050D03*
X347699Y1972250D03*
X367999Y1940250D03*
X369199Y1919750D03*
X369999Y1901950D03*
X388499Y1959550D03*
Y1950550D03*
Y1932950D03*
X389499Y1913050D03*
Y1904050D03*
X349499Y1910050D03*
X348499Y1956550D03*
X347999Y1944550D03*
Y1925550D03*
X348999Y1898050D03*
X406999Y1905050D03*
X405999Y1951550D03*
X405499Y1939550D03*
Y1920550D03*
X406499Y1893050D03*
X385099Y1975950D03*
X420799Y1977250D03*
X399299Y1976750D03*
X367299Y1972950D03*
X420500Y1987000D03*
X403500D03*
X364999Y1987050D03*
X382499Y1987550D03*
X345499D03*
X436499Y50350D03*
Y31350D03*
X466799Y64750D03*
X465799Y43750D03*
Y24750D03*
X499999Y64050D03*
X500499Y47050D03*
X499999Y25550D03*
X432999Y6050D03*
X448499D03*
X467999Y5550D03*
X485499Y6050D03*
X498999D03*
X437499Y71350D03*
X442799Y142450D03*
X441799Y121450D03*
Y102450D03*
X471399Y124550D03*
X470399Y103550D03*
Y84550D03*
X473099Y141050D03*
X499999Y145550D03*
X500499Y126050D03*
Y108550D03*
Y79550D03*
Y94050D03*
X502899Y217150D03*
X504199Y193250D03*
X472999Y214550D03*
X483599Y179350D03*
X446799Y205650D03*
X445799Y184650D03*
Y165650D03*
X474099Y181050D03*
X473099Y160050D03*
X449999Y217050D03*
X430499D03*
X499999Y164550D03*
X466399Y304950D03*
X479299Y297250D03*
X437499Y307050D03*
Y289550D03*
Y275050D03*
X444499Y283050D03*
X463999Y283550D03*
X481499D03*
X495999D03*
X448999Y255550D03*
X469999Y254550D03*
X508499Y255050D03*
X488999Y254550D03*
X438999Y381550D03*
X458499Y382050D03*
X484900Y394700D03*
X485000Y373200D03*
X509999Y382550D03*
X443499Y354050D03*
X464499Y353050D03*
X502999Y353550D03*
X483499Y353050D03*
X498399Y470050D03*
X503699Y419250D03*
X472499Y458050D03*
X468799Y414250D03*
X443199Y440850D03*
X440099Y459250D03*
X431099Y479350D03*
X450300Y404200D03*
X490499Y464050D03*
X490999Y444550D03*
Y427050D03*
Y412550D03*
X454499Y472550D03*
X454999Y438550D03*
X454499Y458050D03*
X453999Y417550D03*
X430099Y551450D03*
X485299Y534550D03*
X508699Y498950D03*
X471499Y493950D03*
X452499Y565050D03*
X456499Y518050D03*
X435499Y519050D03*
X491499Y504050D03*
X490499Y483050D03*
X453999Y509550D03*
X454499Y490050D03*
X504499Y598050D03*
Y580550D03*
Y566050D03*
X479999Y598550D03*
Y581050D03*
Y566550D03*
X509999Y640550D03*
X452499Y597050D03*
Y579550D03*
X427999Y597550D03*
Y580050D03*
Y565550D03*
X506599Y711650D03*
X487299Y716950D03*
X451099Y711650D03*
X450399Y672750D03*
X444799Y687350D03*
X509999Y672550D03*
Y655050D03*
X488499Y691050D03*
Y673550D03*
Y659050D03*
X463999Y691550D03*
Y674050D03*
Y659550D03*
X467699Y772750D03*
X468699Y788350D03*
X472999Y736550D03*
X489599Y752450D03*
X490299Y734550D03*
X453399Y807950D03*
X452099Y781450D03*
Y762450D03*
X435299Y795150D03*
Y777650D03*
Y763150D03*
X437299Y744650D03*
X495999Y795050D03*
X475699Y880450D03*
X479599Y847550D03*
X462999Y884050D03*
Y865050D03*
X453399Y826950D03*
X434799Y833650D03*
Y814650D03*
X464499Y896050D03*
X493499Y884050D03*
Y865050D03*
X493999Y845550D03*
Y813550D03*
Y828050D03*
X506899Y919950D03*
Y900950D03*
X443599Y945650D03*
X442599Y924650D03*
Y905650D03*
X486799Y941050D03*
X485799Y920050D03*
Y901050D03*
X461999Y966050D03*
X462499Y946550D03*
Y914550D03*
Y929050D03*
X494099Y1017350D03*
X493099Y996350D03*
X462499Y1043850D03*
X461999Y985050D03*
X474499Y1115050D03*
X491999Y1115550D03*
X454999D03*
X439499D03*
X501499Y1102550D03*
X463999Y1102050D03*
X481499Y1102550D03*
X444499D03*
X428999D03*
X436999Y1142550D03*
Y1128050D03*
X504399Y1132250D03*
X473099Y1144550D03*
X453499Y1140550D03*
X484499Y1085850D03*
X483499Y1064850D03*
X433599Y1085550D03*
X432599Y1064550D03*
X463499Y1083850D03*
X462499Y1062850D03*
X437599Y1150050D03*
X487099Y1218050D03*
X486499Y1210550D03*
Y1196050D03*
X443199Y1224250D03*
X507199Y1224350D03*
X506599Y1202350D03*
Y1216850D03*
X505399Y1153250D03*
X474099Y1165550D03*
X454499Y1161550D03*
X443799Y1274250D03*
Y1246250D03*
Y1265250D03*
X443199Y1238750D03*
X507199Y1252350D03*
Y1243350D03*
X465499Y1284550D03*
Y1293550D03*
Y1265550D03*
X498299Y1323350D03*
X468999Y1323950D03*
X428499Y1325350D03*
X508599Y1370550D03*
X444899Y1377950D03*
X434499Y1360250D03*
X448099Y1341250D03*
X473999Y1342450D03*
X485599Y1367550D03*
X468699Y1362850D03*
X466699Y1378150D03*
X498899Y1386450D03*
X499199Y1350550D03*
X459699Y1468050D03*
X464199Y1401450D03*
X459999Y1424050D03*
X498899Y1408350D03*
X500899Y1434350D03*
X505899Y1466250D03*
X482599Y1449950D03*
X456399Y1445950D03*
X445099Y1464250D03*
X478299Y1464850D03*
X481499Y1417050D03*
Y1402550D03*
X441499Y1431550D03*
Y1414050D03*
Y1399550D03*
X499699Y1538950D03*
X466999Y1530650D03*
X488299Y1531050D03*
X461399Y1541650D03*
X474299Y1544750D03*
X452199Y1550650D03*
X444299Y1532650D03*
X439599Y1552150D03*
X465999Y1603450D03*
X487099Y1606250D03*
X449199Y1579050D03*
X443799Y1612250D03*
X460199Y1632850D03*
X484999Y1636550D03*
X501399Y1634550D03*
X508199Y1610450D03*
X510100Y1579800D03*
X472299Y1572050D03*
X502199Y1566250D03*
X472499Y1620550D03*
Y1611550D03*
X484200Y1579900D03*
X432499Y1617550D03*
X434500Y1579500D03*
X431999Y1605550D03*
X435300Y1715300D03*
X448399Y1699450D03*
X447699Y1682850D03*
X449599Y1656950D03*
X483599Y1662550D03*
X485599Y1694850D03*
X502899Y1709650D03*
X507399Y1683350D03*
X509199Y1660550D03*
X468499Y1712550D03*
X467999Y1687050D03*
Y1696050D03*
Y1668050D03*
X432400Y1680100D03*
X428600Y1691200D03*
X436799Y1772550D03*
X472699Y1792150D03*
X429499Y1748050D03*
X458499Y1742050D03*
X441499Y1758050D03*
X480999Y1756050D03*
X463999Y1772050D03*
X445499Y1792550D03*
X508200Y1758200D03*
X484999Y1779050D03*
X496999Y1799550D03*
X481299Y1811150D03*
X448099Y1809450D03*
X499999Y1854950D03*
X480499Y1855450D03*
X464999D03*
X443999Y1855950D03*
X476199Y1877450D03*
X434299Y1876050D03*
X446999Y1880050D03*
X492999Y1878050D03*
X504799Y1967550D03*
Y1939550D03*
Y1958550D03*
X505799Y1921050D03*
Y1912050D03*
Y1893050D03*
X475199Y1951950D03*
Y1923950D03*
Y1942950D03*
X476199Y1905450D03*
Y1896450D03*
X459299Y1966850D03*
Y1938850D03*
Y1957850D03*
X460299Y1920350D03*
Y1911350D03*
Y1892350D03*
X433299Y1950550D03*
Y1922550D03*
Y1941550D03*
X434299Y1904050D03*
Y1895050D03*
X445999Y1954550D03*
Y1945550D03*
Y1926550D03*
X446999Y1908050D03*
Y1899050D03*
X493499Y1909050D03*
X492499Y1955550D03*
X491999Y1943550D03*
Y1924550D03*
X492999Y1897050D03*
X509299Y1977250D03*
X493799D03*
X473299D03*
X455799Y1976750D03*
X436299Y1977250D03*
X492500Y1987500D03*
X476000Y1987000D03*
X456500Y1987500D03*
X438999Y1987550D03*
X522899Y64350D03*
Y45350D03*
X587999Y63550D03*
X588499Y46550D03*
X587999Y25050D03*
X541499Y63550D03*
X541999Y46550D03*
X541499Y25050D03*
X516499Y6550D03*
X535999D03*
X551499D03*
X570999Y6050D03*
X588499Y6550D03*
X523899Y85350D03*
X520299Y141450D03*
Y122450D03*
X569099Y112550D03*
X568099Y91550D03*
Y72550D03*
X562799Y146750D03*
Y127750D03*
X587999Y145050D03*
X588499Y125550D03*
X541499Y145050D03*
X541999Y125550D03*
Y108050D03*
Y79050D03*
Y93550D03*
X565999Y199950D03*
X528799D03*
X521299Y162450D03*
X563799Y167750D03*
X587999Y217050D03*
X568499Y217550D03*
X552999D03*
X533499D03*
X588999Y185050D03*
X587999Y164050D03*
X542499Y185050D03*
X541499Y164050D03*
X544799Y293950D03*
X540099Y306550D03*
X516899Y306950D03*
X515499Y284050D03*
X536499Y283050D03*
X525999Y255050D03*
X540499D03*
X572999Y287050D03*
X572499Y306550D03*
X572999Y269550D03*
Y255050D03*
X579899Y375750D03*
X530999Y381550D03*
X520499Y353550D03*
X548100Y362200D03*
X573499Y346550D03*
X572499Y325550D03*
X577899Y460550D03*
X578399Y441050D03*
X577399Y420050D03*
X539799Y466050D03*
X538799Y445050D03*
X576099Y481850D03*
X511299Y449150D03*
X519499Y471550D03*
X518999Y416550D03*
X592499Y478050D03*
Y459050D03*
X592999Y439550D03*
Y422050D03*
Y407550D03*
X556499Y467550D03*
X555999Y412550D03*
X539299Y485550D03*
X576599Y522350D03*
X577099Y502850D03*
X579499Y561550D03*
X558499Y562550D03*
X538999Y562050D03*
X535499Y545050D03*
X514499Y546050D03*
X518999Y508550D03*
X519499Y489050D03*
X555999Y504550D03*
X556499Y485050D03*
X534499Y640050D03*
X586299Y711250D03*
X565699Y710650D03*
X549999Y710050D03*
X547999Y728550D03*
X573499Y690550D03*
Y673050D03*
Y658550D03*
X534499Y672050D03*
Y654550D03*
Y805950D03*
X511199Y782050D03*
X527499Y747150D03*
X525499Y772450D03*
X547499Y799050D03*
Y780050D03*
X547999Y760550D03*
Y743050D03*
X575499Y802050D03*
X575999Y782550D03*
Y765050D03*
X577999Y732050D03*
X575999Y750550D03*
X526499Y851150D03*
X510899Y868150D03*
X578299Y895650D03*
X541399Y873450D03*
Y854450D03*
X512899Y842550D03*
Y823550D03*
X521999Y895550D03*
X522499Y876050D03*
X576499Y842050D03*
X575499Y821050D03*
X583299Y961450D03*
X578299Y914650D03*
X540299Y956850D03*
X539299Y935850D03*
X570899Y965850D03*
Y946850D03*
X521999Y914550D03*
X562999Y898050D03*
X560499Y968050D03*
X560999Y948550D03*
Y916550D03*
Y931050D03*
X516499Y957050D03*
X514499Y975550D03*
X583299Y980450D03*
X534599Y1048550D03*
X571899Y986850D03*
X573499Y1055550D03*
Y1036550D03*
X541899Y1021450D03*
X540899Y1000450D03*
Y981450D03*
X560499Y987050D03*
X560999Y999050D03*
X558999Y1049550D03*
Y1017550D03*
Y1032050D03*
X513999Y1046050D03*
Y1027050D03*
X514499Y1007550D03*
Y990050D03*
X588499Y1101550D03*
X578999Y1114550D03*
X568499Y1101550D03*
X564499Y1116050D03*
X548999D03*
X529499D03*
X511999Y1115550D03*
X553999Y1103050D03*
X538499D03*
X518999D03*
X535599Y1069550D03*
X574499Y1076550D03*
X558499Y1088050D03*
Y1069050D03*
X547099Y1202750D03*
Y1221750D03*
X546499Y1180750D03*
Y1195250D03*
X567999Y1215550D03*
Y1206550D03*
Y1187550D03*
X527999Y1212550D03*
X527499Y1200550D03*
Y1181550D03*
X579299Y1300750D03*
X527499Y1278150D03*
X530499Y1297050D03*
X561099Y1301050D03*
X566399Y1273850D03*
X549399Y1302850D03*
Y1274850D03*
Y1293850D03*
X548799Y1252850D03*
Y1267350D03*
X547099Y1230750D03*
X583299Y1283250D03*
Y1255250D03*
Y1274250D03*
X582699Y1233250D03*
Y1247750D03*
X565999Y1248550D03*
Y1234050D03*
X525999Y1263050D03*
Y1245550D03*
Y1231050D03*
X555699Y1322950D03*
X581999Y1370150D03*
X559099Y1343250D03*
X545099Y1355250D03*
X518499Y1346950D03*
X540399Y1382150D03*
X523999Y1391050D03*
X523499Y1360050D03*
Y1379050D03*
X580999Y1412750D03*
X575699Y1438950D03*
X538799Y1409750D03*
X536799Y1436350D03*
X528499Y1460250D03*
X546099Y1467550D03*
X582999Y1461250D03*
X557499Y1443050D03*
Y1452050D03*
Y1424050D03*
X516999Y1437050D03*
X517499Y1449050D03*
X516999Y1418050D03*
X590599Y1483450D03*
X529799Y1555050D03*
X567999Y1549950D03*
X582299Y1534150D03*
X538999Y1528350D03*
X518899Y1530150D03*
X532499Y1635550D03*
X552099Y1601950D03*
X553399Y1624550D03*
X590799Y1627850D03*
X588000Y1604000D03*
X588099Y1572050D03*
X552199Y1576650D03*
X569499Y1619550D03*
Y1610550D03*
X573400Y1577600D03*
X529499Y1616550D03*
X533800Y1575500D03*
X528999Y1604550D03*
X518499Y1643950D03*
X538299Y1721050D03*
X532599Y1655650D03*
X554199Y1651950D03*
X555199Y1674750D03*
X555399Y1689350D03*
X555899Y1706750D03*
X580299Y1722550D03*
X590599Y1694450D03*
X580799Y1646150D03*
X572999Y1694550D03*
Y1703550D03*
Y1675550D03*
X532499Y1688550D03*
X532999Y1700550D03*
X532499Y1669550D03*
X582599Y1740050D03*
X560399Y1792550D03*
X555500Y1802700D03*
X539499Y1788150D03*
X526499Y1801150D03*
X556199Y1727050D03*
X522300Y1739200D03*
X532499Y1763050D03*
X515499Y1779050D03*
X531799Y1818450D03*
X514199Y1815750D03*
X591499Y1855950D03*
X573999Y1855450D03*
X554499Y1855950D03*
X538999D03*
X517499Y1855450D03*
X588899Y1882350D03*
X562599Y1874450D03*
X519399Y1876750D03*
X533499Y1884050D03*
X575999Y1888050D03*
X587899Y1956850D03*
Y1928850D03*
Y1947850D03*
X588899Y1910350D03*
Y1901350D03*
X561599Y1948950D03*
Y1920950D03*
Y1939950D03*
X562599Y1902450D03*
Y1893450D03*
X546999Y1966850D03*
Y1938850D03*
Y1957850D03*
X547999Y1920350D03*
Y1911350D03*
Y1892350D03*
X518399Y1951250D03*
Y1923250D03*
Y1942250D03*
X519399Y1904750D03*
Y1895750D03*
X532499Y1958550D03*
Y1949550D03*
Y1930550D03*
X533499Y1912050D03*
Y1903050D03*
X575999Y1907050D03*
X576499Y1919050D03*
X574999Y1953550D03*
X575499Y1965550D03*
X574999Y1934550D03*
X585799Y1976250D03*
X570299D03*
X546299Y1977250D03*
X528799Y1976750D03*
X568999Y1987050D03*
X553499D03*
X588499Y1986550D03*
X511999Y1987550D03*
X531500Y1987500D03*
X603999Y54350D03*
Y35350D03*
X651799Y59650D03*
Y40650D03*
X674999Y59050D03*
X675499Y42050D03*
X674999Y20550D03*
X624499Y61550D03*
X624999Y44550D03*
X624499Y23050D03*
X608499Y6550D03*
X625999Y7050D03*
X645499D03*
X660999D03*
X604999Y75350D03*
X603999Y133750D03*
X652799Y80650D03*
X649899Y138350D03*
X674999Y140550D03*
X675499Y121050D03*
Y103550D03*
Y74550D03*
Y89050D03*
X624499Y143050D03*
X624999Y123550D03*
X623899Y202550D03*
X604999Y173750D03*
X603999Y152750D03*
X650899Y178350D03*
X649899Y157350D03*
X662499Y218050D03*
X642999D03*
X625499Y217550D03*
X605499D03*
X675999Y180550D03*
X674999Y159550D03*
X625499Y183050D03*
X624499Y162050D03*
X656499Y307050D03*
X653999Y286550D03*
X627999Y280050D03*
X627499Y299550D03*
X627999Y262550D03*
Y248050D03*
X599799Y385150D03*
X600299Y365650D03*
X599299Y344650D03*
X659899Y363250D03*
X632399Y358750D03*
X635399Y376250D03*
X607399Y380250D03*
X643599Y395950D03*
X655999Y344050D03*
X656499Y324550D03*
X628499Y339550D03*
X628200Y320000D03*
X644099Y450950D03*
X644599Y416950D03*
X644099Y436450D03*
X621499Y466550D03*
X621999Y432550D03*
X621499Y452050D03*
X620999Y411550D03*
X666999Y476550D03*
X643499Y546750D03*
X642499Y525750D03*
X613700Y504600D03*
X621499Y484050D03*
X593499Y499050D03*
X666499Y547050D03*
X666999Y508550D03*
X666499Y528050D03*
X666999Y491050D03*
X642999Y566250D03*
X640599Y604650D03*
X673999Y645150D03*
X645099Y639150D03*
X631999Y639650D03*
X665999Y623550D03*
X620499D03*
Y609050D03*
X595999Y641550D03*
Y624050D03*
Y609550D03*
X674999Y601550D03*
X646999Y584550D03*
X625999Y585050D03*
X606499Y584550D03*
X667499Y568050D03*
X651999Y718350D03*
X648999Y702350D03*
X629099Y714050D03*
X605299Y661750D03*
X609499Y708050D03*
X607499Y726550D03*
X647499Y689050D03*
Y671550D03*
Y657050D03*
X622999Y689550D03*
Y672050D03*
X597999Y690050D03*
X647399Y742150D03*
X653099Y803350D03*
X621499Y767150D03*
X633499Y750150D03*
X606999Y797050D03*
Y778050D03*
X607499Y758550D03*
Y741050D03*
X664999Y805050D03*
Y786050D03*
X665499Y766550D03*
X645799Y816650D03*
X642599Y883250D03*
X641599Y862250D03*
Y843250D03*
X621999Y835050D03*
X612999Y854550D03*
X629499Y853050D03*
Y868550D03*
X613499Y868050D03*
X663499Y896050D03*
X663999Y876550D03*
Y844550D03*
Y859050D03*
X665999Y826050D03*
X639499Y971150D03*
Y952150D03*
X616699Y967250D03*
Y948250D03*
X658999Y959050D03*
X656999Y977550D03*
X603499Y904050D03*
X601499Y954550D03*
Y922550D03*
Y937050D03*
X664499Y936050D03*
X663499Y915050D03*
X673999Y1036550D03*
Y1017550D03*
X674699Y1061450D03*
X611399Y1045650D03*
Y1026650D03*
X617699Y988250D03*
X656499Y1048050D03*
Y1029050D03*
X656999Y1009550D03*
Y992050D03*
X631999Y1001550D03*
X629999Y1052050D03*
Y1020050D03*
Y1034550D03*
X600999Y1002050D03*
X598999Y1052550D03*
Y1020550D03*
Y1035050D03*
X633999Y1103050D03*
X669499Y1116550D03*
X616499Y1115050D03*
X605999Y1102050D03*
X598999Y1114550D03*
X674699Y1080450D03*
X674999Y1134950D03*
X641799Y1137650D03*
X627699Y1143550D03*
X612399Y1066650D03*
X629499Y1090550D03*
Y1071550D03*
X598499Y1091050D03*
Y1072050D03*
X603899Y1157850D03*
X626199Y1183450D03*
X597599Y1196050D03*
X596599Y1215050D03*
X651599Y1203050D03*
X650599Y1182050D03*
X651299Y1174150D03*
X650299Y1153150D03*
X668199Y1173850D03*
X667199Y1152850D03*
X671199Y1213750D03*
X670199Y1192750D03*
X628699Y1164550D03*
X668699Y1227650D03*
X672999Y1303450D03*
X608899Y1305050D03*
X600899Y1238650D03*
X630499Y1243950D03*
X657099Y1272850D03*
X657799Y1288450D03*
X656399Y1307050D03*
X618199Y1296250D03*
Y1268250D03*
Y1287250D03*
X617599Y1246250D03*
Y1260750D03*
X638999Y1286550D03*
Y1295550D03*
Y1267550D03*
X598499Y1280550D03*
X598999Y1292550D03*
X598499Y1261550D03*
X671999Y1324950D03*
X631799Y1322650D03*
X605599Y1326350D03*
X665699Y1337250D03*
X606199Y1338250D03*
X617899Y1360850D03*
X625499Y1383450D03*
X632499Y1347950D03*
X599999Y1382550D03*
X599499Y1351550D03*
Y1370550D03*
X654999Y1385050D03*
X654499Y1373050D03*
Y1354050D03*
X659699Y1445950D03*
X604899Y1407750D03*
X601299Y1447650D03*
X636799Y1461250D03*
X626799Y1432350D03*
X627499Y1406050D03*
X665699Y1462250D03*
X652999Y1435550D03*
Y1418050D03*
Y1403550D03*
X656099Y1479550D03*
X625199Y1489150D03*
X610899Y1496750D03*
X672399Y1508750D03*
X673699Y1535350D03*
X662099Y1549650D03*
X643099Y1541350D03*
X599799Y1544650D03*
X617699Y1530350D03*
X670699Y1603150D03*
X671399Y1625350D03*
X628499Y1636650D03*
X633499Y1615450D03*
X635500Y1603900D03*
X652399Y1575850D03*
X623499Y1564050D03*
X652499Y1618550D03*
Y1609550D03*
X639200Y1576200D03*
X612499Y1615550D03*
X611900Y1577900D03*
X611999Y1603550D03*
X649399Y1644950D03*
X657099Y1668850D03*
X635099Y1691150D03*
X607599Y1716450D03*
X593399Y1668850D03*
X627299Y1659550D03*
X600599Y1645450D03*
X674999Y1676550D03*
X656499Y1697050D03*
X609499Y1692050D03*
Y1675050D03*
X642499Y1709050D03*
X665399Y1752350D03*
X650399Y1771250D03*
X593299Y1760950D03*
X619499Y1803150D03*
X627273Y1793905D03*
X606999Y1745550D03*
X625499Y1725050D03*
X675499Y1757050D03*
X675999Y1769050D03*
X675499Y1738050D03*
X642400Y1800100D03*
X659159Y1792278D03*
X626999Y1800050D03*
X645099Y1877550D03*
X667999Y1870950D03*
X632799Y1820450D03*
X627494Y1829068D03*
X608599Y1810750D03*
X669399Y1855350D03*
X627499Y1855950D03*
X611999D03*
X630699Y1872750D03*
X602799Y1887350D03*
X640999Y1815550D03*
X595199Y1820910D03*
X659549Y1815384D03*
X644049Y1810834D03*
X633837Y1807384D03*
X646799Y1926450D03*
X645399Y1906150D03*
X673899Y1966850D03*
Y1938850D03*
Y1957850D03*
X674899Y1920350D03*
Y1911350D03*
Y1892350D03*
X660299Y1964550D03*
Y1936550D03*
Y1955550D03*
X661299Y1918050D03*
Y1909050D03*
Y1890050D03*
X629699Y1947250D03*
Y1919250D03*
Y1938250D03*
X630699Y1900750D03*
Y1891750D03*
X601799Y1961850D03*
Y1933850D03*
Y1952850D03*
X602799Y1915350D03*
Y1906350D03*
X616499Y1913050D03*
Y1922050D03*
Y1894050D03*
X615499Y1959550D03*
Y1968550D03*
Y1940550D03*
X644999Y1953050D03*
X645499Y1965050D03*
X644999Y1934050D03*
X659299Y1976250D03*
X643799D03*
X622799D03*
X605299Y1975750D03*
X642499Y1987050D03*
X626999D03*
X661999Y1986550D03*
X605999Y1987050D03*
X751499Y48350D03*
X694999Y62650D03*
X757499Y63050D03*
Y44050D03*
X725499Y62050D03*
X725999Y45050D03*
X725499Y23550D03*
X680499Y6550D03*
X697999Y7050D03*
X712499Y6050D03*
X729999Y6550D03*
X749499D03*
X752099Y112150D03*
X738199Y137450D03*
X695999Y102650D03*
X694999Y81650D03*
X699699Y141750D03*
X758499Y84050D03*
X725499Y143550D03*
X725999Y124050D03*
Y106550D03*
Y77550D03*
Y92050D03*
X728899Y204550D03*
X688999Y196550D03*
X700699Y181750D03*
X699699Y160750D03*
X749499Y218550D03*
X729499D03*
X711999Y218050D03*
X677999D03*
X726499Y183550D03*
X725499Y162550D03*
X711999Y307550D03*
Y293050D03*
X723200Y275500D03*
X711499Y252550D03*
X680500Y280700D03*
X682999Y300050D03*
X683499Y263050D03*
Y248550D03*
X748000Y357500D03*
X749899Y398550D03*
X711499Y344550D03*
X711999Y325050D03*
X683999Y340050D03*
X682999Y319050D03*
X713699Y455450D03*
X713199Y474950D03*
X712699Y434450D03*
X750399Y453550D03*
X750899Y419550D03*
X750399Y439050D03*
X694999Y480550D03*
X737999Y467050D03*
X691399Y548350D03*
X755699Y528650D03*
X756199Y509150D03*
X755199Y488150D03*
X754499Y564650D03*
X713099Y561550D03*
X713599Y542050D03*
X712599Y521050D03*
X713199Y489450D03*
X695499Y521050D03*
X695999Y501550D03*
X737999Y559050D03*
X738499Y539550D03*
Y522050D03*
Y507550D03*
X738999Y488050D03*
X691899Y588850D03*
X692399Y569350D03*
X754999Y605150D03*
X755499Y585650D03*
X717099Y636050D03*
X729699Y640350D03*
X731499Y604050D03*
Y586550D03*
Y572050D03*
X690499Y623050D03*
X744999Y626550D03*
X721499Y617550D03*
X699999Y610050D03*
X757400Y686300D03*
X720899Y712250D03*
X732499Y729250D03*
X681899Y713650D03*
X679299Y703050D03*
X727099Y715050D03*
X739399Y688150D03*
X747999Y670750D03*
X723499Y654850D03*
X693999Y648150D03*
X754999Y694050D03*
X702999Y688050D03*
Y670550D03*
Y656050D03*
X678499Y688550D03*
Y671050D03*
X749999Y700050D03*
X750000Y755500D03*
X710899Y751150D03*
X696299Y741850D03*
X685999Y780050D03*
X694599Y763450D03*
X743099Y785350D03*
X733799Y761450D03*
X716599Y736850D03*
X723999Y802350D03*
Y783350D03*
X687099Y804650D03*
X706999Y811550D03*
Y792550D03*
X707499Y773050D03*
X728499Y841850D03*
X724999Y823350D03*
X688099Y844650D03*
X687099Y823650D03*
X729999Y881850D03*
Y862850D03*
X751599Y887350D03*
X705999Y851050D03*
Y865550D03*
X707999Y832550D03*
X751499Y855550D03*
Y836550D03*
X751999Y817050D03*
X707399Y918550D03*
Y899550D03*
X678299Y978350D03*
X730999Y902850D03*
X688099Y936350D03*
X687099Y915350D03*
Y896350D03*
X724699Y976250D03*
X723699Y955250D03*
Y936250D03*
X752599Y927350D03*
X751599Y906350D03*
X706499Y942550D03*
X749999Y965550D03*
Y946550D03*
X751399Y1023550D03*
Y1004550D03*
X752399Y1052550D03*
X734999Y1030550D03*
Y1045050D03*
X713999Y1049050D03*
Y1031550D03*
Y1017050D03*
X678299Y997350D03*
X694999Y993050D03*
X692999Y1043550D03*
Y1011550D03*
Y1026050D03*
X750999Y986550D03*
X734999Y1062550D03*
X713499Y1068550D03*
X737999Y1119050D03*
X727499Y1106050D03*
X720499Y1118550D03*
X709999Y1105550D03*
X700499Y1118550D03*
X689999Y1105550D03*
X727499Y1132650D03*
X704299D03*
X692499Y1082050D03*
Y1063050D03*
X753999Y1100050D03*
X747000Y1159000D03*
X713599Y1214650D03*
X756799Y1217650D03*
X758799Y1190150D03*
Y1199150D03*
X717999Y1169150D03*
X716999Y1148150D03*
X714399Y1199750D03*
X713399Y1178750D03*
X735999Y1220550D03*
Y1206050D03*
X737999Y1187550D03*
Y1178550D03*
Y1159550D03*
X695999Y1217550D03*
Y1203050D03*
X697999Y1184550D03*
X697499Y1172550D03*
Y1153550D03*
X684299Y1249550D03*
X740799Y1298750D03*
X723499Y1292650D03*
Y1278150D03*
X725499Y1250650D03*
Y1259650D03*
Y1231650D03*
X755399Y1300650D03*
Y1286150D03*
X757399Y1258650D03*
Y1267650D03*
Y1239650D03*
X756799Y1232150D03*
X709699Y1264550D03*
X708699Y1243550D03*
X740499Y1252550D03*
Y1270050D03*
X695999Y1235050D03*
X739199Y1348950D03*
X742099Y1320650D03*
X719199Y1322350D03*
X695999Y1323350D03*
X677999Y1347550D03*
X680299Y1365850D03*
X713899Y1386450D03*
X707899Y1346250D03*
X734199Y1373850D03*
X694999Y1388050D03*
Y1379050D03*
Y1360050D03*
X702299Y1404450D03*
X736199Y1399050D03*
X741099Y1450250D03*
X737799Y1428350D03*
X716899Y1459850D03*
X700899Y1450250D03*
X681299Y1393150D03*
X678299Y1425050D03*
X686999Y1468850D03*
X719499Y1446650D03*
X721899Y1419050D03*
X754999Y1420050D03*
Y1437550D03*
X692999Y1421050D03*
Y1406550D03*
X741099Y1498150D03*
X729199Y1492750D03*
X716199Y1503050D03*
X735799Y1533650D03*
X714599Y1533950D03*
X708899Y1549250D03*
X685299Y1551950D03*
X747199Y1509150D03*
X755499Y1507550D03*
X734499Y1563550D03*
X722199Y1564250D03*
X706700Y1579900D03*
X698599Y1568550D03*
X681299Y1579150D03*
X693599Y1602450D03*
X686699Y1638650D03*
X742000Y1560000D03*
X743400Y1578700D03*
X719999Y1605050D03*
X751300Y1604900D03*
X732999Y1620050D03*
X756299Y1679050D03*
X738799Y1677250D03*
X750099Y1694950D03*
X756499Y1712150D03*
X739199Y1716750D03*
X721199Y1723750D03*
X727399Y1694350D03*
X717099Y1702450D03*
X693099Y1722350D03*
X691999Y1660550D03*
X751899Y1752150D03*
X747799Y1766750D03*
X729499Y1778750D03*
X729999Y1756450D03*
X747499Y1734350D03*
X702599Y1730550D03*
X709099Y1751850D03*
X690499Y1744950D03*
X694599Y1768450D03*
X715999Y1763050D03*
Y1772050D03*
Y1744050D03*
X693549Y1793134D03*
X706549Y1793634D03*
X744049Y1791634D03*
X740549Y1802634D03*
X753949Y1798194D03*
X717000Y1812384D03*
X705000Y1811900D03*
X686999Y1870250D03*
X728099Y1844750D03*
X747599Y1844250D03*
X743799Y1888850D03*
X728299D03*
X753699Y1879250D03*
X732199Y1878750D03*
X744699Y1868450D03*
X758399Y1868350D03*
X723199Y1867950D03*
X743399Y1855850D03*
X725899Y1855350D03*
X690899Y1855850D03*
X706399D03*
X697999Y1844550D03*
X732999Y1868550D03*
X711500Y1817700D03*
X704300Y1828400D03*
X686473Y1818375D03*
X740549Y1810384D03*
X750000Y1965500D03*
X696299Y1898850D03*
X716599Y1918450D03*
X728799Y1933050D03*
X709199Y1962950D03*
X698299Y1948050D03*
X676399Y1901150D03*
X695299Y1926450D03*
X711899Y1944050D03*
X736799Y1919450D03*
X728799Y1908150D03*
X705599Y1891850D03*
X730499Y1954650D03*
X755299Y1902150D03*
X739799D03*
X685499Y1959050D03*
Y1968050D03*
Y1940050D03*
X755500Y1914500D03*
X721499Y1974550D03*
X696299Y1976250D03*
X678799Y1975750D03*
X754999Y1987550D03*
X737499Y1987050D03*
X717999Y1987550D03*
X702499D03*
X679499Y1987050D03*
X774399Y54050D03*
X763399Y24150D03*
X817599Y43750D03*
X824899Y25150D03*
X813299Y68350D03*
Y49350D03*
X796999Y65550D03*
X797499Y48550D03*
X796999Y27050D03*
X764999Y6550D03*
X784499Y6050D03*
X801999Y6550D03*
X818999Y6050D03*
X836499Y6550D03*
X840499Y55050D03*
X839999Y46050D03*
X840999Y62550D03*
X778399Y105250D03*
X775399Y80250D03*
X821199Y137450D03*
X813299Y110850D03*
X805899Y126150D03*
X767399Y140150D03*
X796599Y123450D03*
X814299Y89350D03*
X796999Y147050D03*
X797499Y127550D03*
Y110050D03*
Y81050D03*
Y95550D03*
X837499Y138550D03*
X838499Y145050D03*
X841499Y71550D03*
X760799Y181950D03*
X779399Y200550D03*
X786499Y219050D03*
X800999Y216550D03*
X766999Y219050D03*
X797999Y187050D03*
X796999Y166050D03*
X838999Y313550D03*
X821499Y314050D03*
X784478Y355424D03*
Y359924D03*
X781478Y363924D03*
X776978D03*
X772478Y359924D03*
Y363924D03*
X839299Y390950D03*
X819299Y394250D03*
X838499Y352050D03*
X840299Y430950D03*
X839299Y409950D03*
X820299Y434250D03*
X819299Y413250D03*
X802999Y466050D03*
X774999Y476550D03*
Y462050D03*
X825399Y540950D03*
X825899Y521450D03*
X824899Y500450D03*
X835599Y564050D03*
X834599Y543050D03*
X802999Y558050D03*
X803499Y538550D03*
Y521050D03*
Y506550D03*
X803999Y487050D03*
X775499Y553550D03*
X774499Y532550D03*
X774999Y494050D03*
X774499Y513550D03*
X835099Y583550D03*
X814499Y601550D03*
Y584050D03*
Y569550D03*
X789999Y602050D03*
Y584550D03*
Y570050D03*
X785499Y641050D03*
X777499Y638050D03*
X771800Y686600D03*
X786500Y686100D03*
X798000Y686400D03*
X764599Y655750D03*
X777499Y664550D03*
X794999D03*
X806300Y670600D03*
X841000Y671100D03*
X766499Y699050D03*
X782999Y699550D03*
X836149Y714050D03*
X766499Y705550D03*
X771196Y764382D03*
Y760382D03*
X775696Y764382D03*
X780196D03*
X783196Y760382D03*
Y755882D03*
X799385Y761436D03*
X778999Y806950D03*
X763099Y796350D03*
X835999Y799050D03*
Y781550D03*
Y767050D03*
X811499Y799550D03*
Y782050D03*
Y767550D03*
X837799Y754150D03*
X825199Y850850D03*
X827699Y892450D03*
Y873450D03*
X776199Y879250D03*
X775199Y858250D03*
Y839250D03*
X800999Y892550D03*
X802999Y874050D03*
X801999Y853050D03*
Y834050D03*
X802499Y814550D03*
X828699Y913450D03*
X826999Y963150D03*
X773199Y960650D03*
X772199Y939650D03*
Y920650D03*
X800499Y944050D03*
Y963050D03*
X800999Y924550D03*
Y907050D03*
Y1037550D03*
Y1005550D03*
Y1020050D03*
X827999Y1003150D03*
X826999Y982150D03*
X777899Y1028050D03*
X776899Y1007050D03*
Y988050D03*
X801499Y984050D03*
X783999Y1096550D03*
X760999Y1095550D03*
X789499Y1099550D03*
X773499Y1101050D03*
X769499D03*
X773499Y1105050D03*
X769499D03*
X836149Y1118550D03*
X783333Y1157392D03*
Y1161892D03*
X780333Y1165892D03*
X775833D03*
X771333Y1161892D03*
Y1165892D03*
X808299Y1175850D03*
X806599Y1189750D03*
X803599Y1211050D03*
X831499Y1209550D03*
Y1200550D03*
Y1181550D03*
X789499Y1225050D03*
X791499Y1206550D03*
X790999Y1194550D03*
Y1175550D03*
X839999Y1157550D03*
X826199Y1294450D03*
X828199Y1267850D03*
X788999Y1278150D03*
X791999Y1294450D03*
X808199Y1290350D03*
Y1275850D03*
X810199Y1248350D03*
Y1257350D03*
Y1229350D03*
X829499Y1242550D03*
Y1228050D03*
X789499Y1257050D03*
Y1239550D03*
X825500Y1379000D03*
X831499Y1324950D03*
X795299Y1326650D03*
X822199Y1335250D03*
X819199Y1353550D03*
X798299Y1344250D03*
X779399Y1361850D03*
X762499Y1335550D03*
Y1353050D03*
X799999Y1340550D03*
Y1358050D03*
X806499Y1390550D03*
X803299Y1426650D03*
X773999Y1393450D03*
X763399Y1401450D03*
X781999Y1434650D03*
X805899Y1464250D03*
X771399Y1474550D03*
X806499Y1408050D03*
X834499Y1397550D03*
X836600Y1416500D03*
X769300Y1488100D03*
X779000Y1488400D03*
X786500Y1488600D03*
X801300Y1489000D03*
X770999Y1500050D03*
X780499D03*
X839499Y1523550D03*
X773499Y1509050D03*
X769499D03*
X786999Y1506550D03*
X785827Y1561296D03*
Y1565796D03*
X782827Y1569796D03*
X778327D03*
X773327Y1565796D03*
X773827Y1569796D03*
X813300Y1604100D03*
X827199Y1622750D03*
X841499Y1638950D03*
X803599Y1618350D03*
X826499Y1609050D03*
X825999Y1578050D03*
X839899Y1562050D03*
X829200Y1719800D03*
X824100Y1719900D03*
X819400Y1721900D03*
X837199Y1660550D03*
X814599Y1642650D03*
X776999Y1647650D03*
X797299Y1646650D03*
X802899Y1670550D03*
X839199Y1683550D03*
X808899Y1698450D03*
X779999Y1717050D03*
X770399Y1699650D03*
X765099Y1664950D03*
X823499Y1693050D03*
Y1702050D03*
Y1674050D03*
X782999Y1687050D03*
X783499Y1699050D03*
X782999Y1668050D03*
X819200Y1727100D03*
X808299Y1755250D03*
X794499Y1734550D03*
X770099Y1730350D03*
X779899Y1748150D03*
X787900Y1758800D03*
X765600Y1756800D03*
X827999Y1791550D03*
X829799Y1856350D03*
X809299D03*
X791799Y1855850D03*
X801099Y1844750D03*
X785599D03*
X765099D03*
X780799Y1888850D03*
X763299Y1888350D03*
X833100Y1878500D03*
X806199Y1879250D03*
X788699Y1878750D03*
X769199Y1879250D03*
X833199Y1868450D03*
X818900Y1870800D03*
X797199Y1868450D03*
X779699Y1867950D03*
X779399Y1855850D03*
X763899D03*
X783814Y1967213D03*
Y1971713D03*
X783499Y1907050D03*
X774499Y1908050D03*
X765999D03*
X838999Y1928550D03*
X790499Y1913050D03*
X775999Y1916050D03*
X840999Y1970550D03*
X768499Y1917550D03*
X784016Y1975708D03*
X775814Y1975699D03*
X771814Y1975713D03*
X813599Y1979950D03*
X789299Y1983850D03*
X829499Y1980250D03*
X829999Y1987550D03*
X812499Y1987050D03*
X792999Y1987550D03*
X777499D03*
X902999Y22050D03*
X917499Y21550D03*
X909499D03*
X902499Y35050D03*
X909999Y35550D03*
X916499Y36050D03*
X844799Y19850D03*
X860799Y24150D03*
X885999Y21150D03*
X855999Y6550D03*
X871499D03*
X890999Y6050D03*
X908499Y6550D03*
X923999Y6050D03*
X854499Y39550D03*
X865499D03*
X883999Y39050D03*
X904999Y61550D03*
Y67550D03*
X905499Y56550D03*
X890700Y132500D03*
X872100Y132700D03*
X854300Y132600D03*
X891999Y146050D03*
X856499Y71050D03*
X881499Y70550D03*
X866999D03*
X904499Y74050D03*
X906999Y224150D03*
X887400Y233555D03*
X871786Y233924D03*
Y218924D03*
Y203924D03*
X907999Y264150D03*
X906999Y243150D03*
X906399Y314250D03*
Y295250D03*
X863999Y313550D03*
X887400Y259700D03*
X879878Y247724D03*
X907399Y335250D03*
X875799Y386250D03*
X904999Y385050D03*
Y370550D03*
X854499Y387550D03*
Y373050D03*
X858400Y352300D03*
X847999Y352550D03*
X870600Y346700D03*
X876799Y426250D03*
X875799Y405250D03*
X884399Y462450D03*
Y443450D03*
X905499Y462050D03*
X904499Y441050D03*
Y422050D03*
X904999Y402550D03*
X854999Y464550D03*
X853999Y443550D03*
X854499Y405050D03*
X853999Y424550D03*
X861199Y546050D03*
X860199Y525050D03*
X885399Y483450D03*
X914699Y524650D03*
X913699Y503650D03*
Y484650D03*
X860699Y565550D03*
X898999Y622050D03*
Y604550D03*
X860499Y607550D03*
X861800Y591200D03*
X918999Y641550D03*
X870719Y609705D03*
X894000Y642400D03*
X870719Y639705D03*
X870773Y624705D03*
X866499Y724550D03*
X895999Y720050D03*
Y702550D03*
X900999Y670050D03*
Y652550D03*
X918499Y712050D03*
X918999Y673550D03*
X918499Y693050D03*
X918999Y656050D03*
X887401Y665000D03*
X881200Y652100D03*
X859999Y713050D03*
X871385Y719436D03*
X871786Y709482D03*
X871499Y689436D03*
X871786Y679436D03*
X860796Y678632D03*
X921399Y796350D03*
X921899Y776850D03*
Y759350D03*
Y744850D03*
X884499Y799050D03*
Y781550D03*
Y767050D03*
X859999Y799550D03*
Y782050D03*
Y767550D03*
X919499Y733050D03*
X856299Y753150D03*
X846799Y754150D03*
X865000Y752100D03*
X889699Y876050D03*
X847799Y828250D03*
X857099Y873450D03*
X920399Y886850D03*
Y869350D03*
Y854850D03*
X922399Y836350D03*
X921399Y815350D03*
X898499Y862050D03*
Y844550D03*
Y830050D03*
X873999Y862550D03*
Y845050D03*
Y830550D03*
X886999Y947250D03*
Y907350D03*
X867199Y941350D03*
X866199Y920350D03*
Y901350D03*
X850999Y962550D03*
Y943550D03*
X919899Y925350D03*
X920899Y946350D03*
X919899Y906350D03*
X851999Y983550D03*
X921499Y1031050D03*
X920999Y1050550D03*
X921499Y1013550D03*
Y999050D03*
X870468Y1030227D03*
X880033Y1058592D03*
X886919Y1044478D03*
X870298Y1045227D03*
X870777Y1014948D03*
X921999Y1090550D03*
X920999Y1069550D03*
X887400Y1070600D03*
X859999Y1118550D03*
X841999D03*
X845799Y1190450D03*
X849799Y1199750D03*
X846499Y1170450D03*
X897299Y1182450D03*
X887999Y1209350D03*
X871399Y1201850D03*
Y1210850D03*
Y1182850D03*
X892499Y1224550D03*
X851999Y1218550D03*
X856400Y1157700D03*
X848999Y1158050D03*
X863300Y1153800D03*
X872099Y1268150D03*
X871399Y1291450D03*
X860099Y1295450D03*
X869399Y1243850D03*
Y1229350D03*
X890499Y1285550D03*
Y1271050D03*
X892499Y1252550D03*
Y1243550D03*
X850499Y1300050D03*
Y1282550D03*
Y1268050D03*
X852499Y1249550D03*
X851999Y1237550D03*
X875399Y1322650D03*
X868499Y1392550D03*
X890999Y1336550D03*
Y1354050D03*
X841999Y1341050D03*
Y1358550D03*
X894499Y1423550D03*
Y1441050D03*
X868499Y1410050D03*
X886913Y1449010D03*
X879727Y1463696D03*
X871836Y1450460D03*
Y1435460D03*
Y1420460D03*
X914599Y1521650D03*
X910899Y1549250D03*
X894499Y1522050D03*
Y1539550D03*
X895499Y1488050D03*
X902759Y1509585D03*
X861999Y1522550D03*
X843999Y1523550D03*
X887499Y1476050D03*
X865300Y1557700D03*
X923599Y1634350D03*
X909700Y1576400D03*
X907500Y1604000D03*
X908899Y1630050D03*
X868099Y1635650D03*
X887299Y1620050D03*
X886900Y1604100D03*
X873099Y1572550D03*
X850099Y1572250D03*
X849900Y1605100D03*
X852499Y1621350D03*
X866499Y1603050D03*
Y1612050D03*
X864000Y1578200D03*
X858400Y1561900D03*
X850499Y1562050D03*
X879200Y1698700D03*
X879900Y1709300D03*
X883900Y1709500D03*
X855350Y1703201D03*
X914899Y1657550D03*
X922599Y1682150D03*
X903599Y1686850D03*
X895999Y1661250D03*
X877699Y1646650D03*
X855799Y1658250D03*
X882999Y1678250D03*
X864099Y1683550D03*
X842799Y1701150D03*
X875900Y1709500D03*
X902900Y1709800D03*
X882200Y1744800D03*
X886400Y1744400D03*
X842500Y1799000D03*
X892700Y1727800D03*
X879399Y1798150D03*
X911299Y1800850D03*
X864000Y1748000D03*
X866699Y1770950D03*
X853799Y1790850D03*
X844499Y1788050D03*
X892700Y1736500D03*
X863099Y1813150D03*
X903299Y1814750D03*
X894999Y1829050D03*
X922899Y1853650D03*
X905299Y1852650D03*
X900299Y1876950D03*
X842199Y1879250D03*
X914999Y1887050D03*
Y1868050D03*
X862499Y1823550D03*
X854977Y1818994D03*
X887401Y1881500D03*
X894000Y1868452D03*
X887499Y1855550D03*
X869999Y1855972D03*
X871836Y1840972D03*
X869634Y1826876D03*
X864414Y1940050D03*
X914899Y1912450D03*
X916599Y1942650D03*
X897599Y1938750D03*
X914899Y1972250D03*
X873399Y1963650D03*
X904299Y1954950D03*
X897299Y1904150D03*
X907599Y1930050D03*
X915499Y1899050D03*
X861414Y1928550D03*
X843999D03*
X856999Y1970050D03*
X849999Y1970550D03*
X865200Y1968000D03*
X879399Y1974550D03*
X850499Y1977950D03*
X868699Y1983250D03*
X921499Y1986550D03*
X901999Y1987050D03*
X864999D03*
X849499D03*
X884499Y1986550D03*
X974699Y64650D03*
X977399Y44050D03*
X954799Y17850D03*
X974699Y21450D03*
X991399Y22450D03*
X1002699Y40050D03*
X991999Y56050D03*
X941499Y6550D03*
X960999D03*
X976499D03*
X995999Y6050D03*
X967499Y47050D03*
Y56050D03*
Y64050D03*
X945499Y33550D03*
X940499Y33050D03*
X929999Y32550D03*
X928499Y51550D03*
X943499Y48050D03*
Y55050D03*
X928999Y56050D03*
X928499Y60550D03*
X928999Y65550D03*
X942999Y61550D03*
Y66550D03*
X983099Y83650D03*
X1005299Y71350D03*
X977699Y109150D03*
X994399Y101250D03*
X981099Y123450D03*
X939199Y142050D03*
X968399Y137150D03*
X967999Y73050D03*
Y82050D03*
X943499Y72550D03*
Y78050D03*
X988699Y174350D03*
X967399Y180350D03*
X956099Y181350D03*
X958799Y167350D03*
X1004799Y231450D03*
X1005299Y211950D03*
Y194450D03*
Y179950D03*
X952799Y231150D03*
Y213650D03*
Y199150D03*
X982999Y203550D03*
Y221050D03*
Y189050D03*
X932499Y223550D03*
Y206050D03*
Y191550D03*
X1005299Y305450D03*
Y290950D03*
X1005799Y271450D03*
X1004799Y250450D03*
X952799Y310150D03*
X953299Y290650D03*
X952299Y269650D03*
Y250650D03*
X983999Y316050D03*
Y301550D03*
X933499Y304050D03*
X983499Y280550D03*
X982499Y259550D03*
Y240550D03*
X932999Y283050D03*
X931999Y262050D03*
Y243050D03*
X1005799Y382450D03*
X1004799Y361450D03*
X1005299Y322950D03*
X1004799Y342450D03*
X952299Y380650D03*
X952799Y342150D03*
X952299Y361650D03*
X952799Y324650D03*
X984499Y393050D03*
X983499Y372050D03*
Y353050D03*
X983999Y333550D03*
X933999Y395550D03*
X932999Y374550D03*
X933499Y336050D03*
X932999Y355550D03*
X933499Y318550D03*
X966199Y473350D03*
X1000699Y482350D03*
Y463350D03*
X954799Y451650D03*
Y434150D03*
Y419650D03*
X953299Y401650D03*
X983499Y464050D03*
X983999Y427050D03*
Y444550D03*
Y412550D03*
X933499Y447050D03*
X932999Y466550D03*
X933499Y429550D03*
Y415050D03*
X967199Y513350D03*
X966199Y492350D03*
X1001699Y503350D03*
X1003499Y546350D03*
X1003999Y526850D03*
X951299Y560150D03*
Y541150D03*
X951799Y521650D03*
Y504150D03*
Y489650D03*
X985999Y536550D03*
Y554050D03*
Y522050D03*
X935499Y556550D03*
Y539050D03*
Y524550D03*
X984499Y504050D03*
X983499Y483050D03*
X933999Y506550D03*
X932999Y485550D03*
X967799Y606350D03*
X966799Y585350D03*
Y566350D03*
X1005999Y636350D03*
Y618850D03*
X1004499Y586350D03*
X1005999Y604350D03*
X1003499Y565350D03*
X950299Y631650D03*
Y614150D03*
Y599650D03*
X952299Y581150D03*
X969499Y639050D03*
X986499Y613550D03*
X985499Y592550D03*
Y573550D03*
X935999Y616050D03*
X934999Y595050D03*
Y576050D03*
X949799Y670150D03*
X950799Y691150D03*
X949799Y651150D03*
X969999Y730550D03*
X968999Y709550D03*
Y690550D03*
X969499Y653550D03*
Y671050D03*
Y795750D03*
X969999Y776250D03*
Y758750D03*
Y744250D03*
X994499Y803550D03*
Y784550D03*
X994999Y747550D03*
Y765050D03*
Y733050D03*
X943999Y806050D03*
X944499Y767550D03*
X943999Y787050D03*
X944499Y750050D03*
Y735550D03*
X970499Y879750D03*
Y862250D03*
Y847750D03*
Y835750D03*
X969499Y814750D03*
X992999Y894550D03*
X993499Y857550D03*
Y875050D03*
Y843050D03*
X942999Y877550D03*
Y860050D03*
Y845550D03*
X995499Y824550D03*
X944999Y827050D03*
X994499Y973550D03*
Y956050D03*
Y941550D03*
X949299Y977450D03*
X970999Y939250D03*
X969999Y918250D03*
Y899250D03*
X993999Y934550D03*
X992999Y913550D03*
X943499Y937050D03*
X942499Y916050D03*
Y897050D03*
X994999Y1033050D03*
Y1045050D03*
X993999Y1012050D03*
Y993050D03*
X948799Y1047950D03*
Y1028950D03*
X949299Y1009450D03*
Y991950D03*
X971499Y1048050D03*
X971999Y1011050D03*
Y1028550D03*
Y996550D03*
X949799Y1068950D03*
Y1080950D03*
X998599Y1128450D03*
Y1110950D03*
Y1096450D03*
X950699Y1139750D03*
Y1122250D03*
Y1107750D03*
X975999Y1115550D03*
Y1133050D03*
Y1101050D03*
X925499Y1135550D03*
Y1118050D03*
Y1103550D03*
X972499Y1088050D03*
X971499Y1067050D03*
X999099Y1214450D03*
Y1199950D03*
Y1187950D03*
X998099Y1147950D03*
Y1166950D03*
X951199Y1225750D03*
Y1211250D03*
Y1199250D03*
X950199Y1159250D03*
Y1178250D03*
X976499Y1219050D03*
Y1204550D03*
X925999Y1221550D03*
Y1207050D03*
X976499Y1192550D03*
X975499Y1171550D03*
Y1152550D03*
X925999Y1195050D03*
X924999Y1174050D03*
Y1155050D03*
X999599Y1291450D03*
X998599Y1270450D03*
Y1251450D03*
X999099Y1231950D03*
X951699Y1302750D03*
X950699Y1281750D03*
Y1262750D03*
X951199Y1243250D03*
X976999Y1296050D03*
X975999Y1275050D03*
Y1256050D03*
X976499Y1236550D03*
X926499Y1298550D03*
X925499Y1277550D03*
X925999Y1239050D03*
X925499Y1258550D03*
X975100Y1342600D03*
X1000700Y1358100D03*
X996500Y1324800D03*
X952499Y1361850D03*
X944000Y1391900D03*
X943799Y1380850D03*
Y1342950D03*
X965099Y1324350D03*
X928499Y1325350D03*
X976499Y1377050D03*
Y1362550D03*
X925999Y1379550D03*
Y1365050D03*
X973500Y1474000D03*
X971500Y1467500D03*
X971700Y1457800D03*
Y1462300D03*
X972000Y1442000D03*
Y1437500D03*
X971700Y1448300D03*
Y1452800D03*
X962500Y1436500D03*
Y1441000D03*
X952800Y1437500D03*
Y1442000D03*
X962000Y1466500D03*
X966000Y1475000D03*
X952300Y1467500D03*
X958800Y1472500D03*
X962200Y1447300D03*
Y1451800D03*
X952500Y1448300D03*
Y1452800D03*
X962200Y1456800D03*
Y1461300D03*
X952500Y1457800D03*
Y1462300D03*
X992500Y1397300D03*
X964400Y1409700D03*
X946700Y1426500D03*
X994200Y1421500D03*
X924999Y1471050D03*
X926499Y1456550D03*
X925499Y1435550D03*
X925999Y1397050D03*
X925499Y1416550D03*
X972549Y1502300D03*
Y1506800D03*
X973500Y1483000D03*
Y1478500D03*
X973200Y1488300D03*
X972700Y1497300D03*
X966000Y1479500D03*
Y1484000D03*
X958800Y1477000D03*
Y1481500D03*
X965700Y1489300D03*
X960200Y1495300D03*
X958500Y1486800D03*
X951500Y1495300D03*
X960049Y1500300D03*
X951349D03*
X960049Y1504800D03*
X951349D03*
X973200Y1516400D03*
X972500Y1529100D03*
X966600D03*
X961400Y1528700D03*
X961900Y1522400D03*
X967100Y1522800D03*
X973000D03*
X962100Y1516000D03*
X967300Y1516400D03*
X972700Y1534800D03*
X972000Y1547500D03*
X966100D03*
X960900Y1547100D03*
X961400Y1540800D03*
X966600Y1541200D03*
X972500D03*
X961600Y1534400D03*
X966800Y1534800D03*
X972700Y1553300D03*
X961600Y1552900D03*
X966800Y1553300D03*
X944000Y1511300D03*
X943199Y1531650D03*
X924499Y1541550D03*
X924999Y1503050D03*
X924499Y1522550D03*
X924999Y1485550D03*
X972000Y1566000D03*
X966100D03*
X960900Y1565600D03*
X961400Y1559300D03*
X966600Y1559700D03*
X972500D03*
X973000Y1572800D03*
X972300Y1585500D03*
X966400D03*
X961200Y1585100D03*
X961700Y1578800D03*
X966900Y1579200D03*
X972800D03*
X961900Y1572400D03*
X967100Y1572800D03*
X972400Y1592000D03*
X966500D03*
X961300Y1591600D03*
X972200Y1598400D03*
X966300D03*
X961100Y1598000D03*
X960600Y1604300D03*
X971700Y1604700D03*
X965800D03*
X944499Y1632650D03*
X925599Y1612050D03*
X933199Y1577550D03*
X925499Y1562550D03*
X989999Y1718050D03*
X958799Y1715750D03*
X957799Y1646950D03*
X955499Y1690850D03*
X941499Y1679550D03*
X940499Y1656950D03*
X931499Y1702050D03*
X941800Y1787700D03*
X934200Y1793500D03*
X993299Y1734350D03*
X994999Y1748950D03*
X976600Y1757100D03*
X965349Y1742000D03*
X949799Y1756250D03*
X976399Y1772250D03*
X954499Y1783550D03*
X941499Y1776250D03*
X932199Y1801850D03*
X971000Y1803000D03*
X999999Y1775250D03*
X976399Y1791150D03*
X993499Y1805550D03*
X928000Y1818500D03*
X1003599Y1846650D03*
X995699Y1858950D03*
X971500Y1871500D03*
X937199Y1869950D03*
X993499Y1824550D03*
Y1833550D03*
X987999Y1971950D03*
Y1949050D03*
X1000999Y1946350D03*
X991999Y1915750D03*
X966799Y1892150D03*
X974699Y1914450D03*
X945199Y1946350D03*
X955799Y1951950D03*
X954099Y1915450D03*
X938199Y1917150D03*
X1002500Y1953500D03*
X1001599Y1921450D03*
X992299Y1929050D03*
X989999Y1962650D03*
X980999Y1933350D03*
X947499Y1936050D03*
X946199Y1966650D03*
X937499Y1893850D03*
X971499Y1956050D03*
Y1965050D03*
Y1937050D03*
X930999Y1950050D03*
X931499Y1962050D03*
X930999Y1931050D03*
X955499Y1893050D03*
Y1902050D03*
X953799Y1977950D03*
X930199Y1979550D03*
X1005000Y1980500D03*
X994999Y1986550D03*
X973999D03*
X956499Y1986050D03*
X936999Y1986550D03*
X1022000Y15500D03*
X1013499Y6550D03*
X1020499Y50550D03*
X1020999Y33050D03*
X1010599Y115550D03*
X1020499Y122550D03*
X1020999Y105050D03*
Y85550D03*
Y70050D03*
X1021499Y141050D03*
X1020999Y230550D03*
X1021499Y213050D03*
Y193550D03*
Y178050D03*
X1020999Y158550D03*
Y304550D03*
Y289050D03*
X1020499Y269550D03*
X1020999Y252050D03*
X1020499Y341550D03*
X1020999Y324050D03*
X1020499Y391550D03*
X1020999Y374050D03*
X1007299Y432450D03*
Y414950D03*
Y400450D03*
X1020499Y463550D03*
X1020999Y446050D03*
Y426550D03*
Y411050D03*
X1021999Y558550D03*
Y539050D03*
Y523550D03*
X1021499Y504050D03*
X1021999Y486550D03*
X1021499Y576050D03*
X1020999Y642550D03*
X1020499Y623050D03*
X1020999Y605550D03*
X1020499Y695050D03*
X1020999Y677550D03*
Y658050D03*
Y720050D03*
X1020499Y809550D03*
X1020999Y792050D03*
Y772550D03*
Y757050D03*
X1020499Y737550D03*
Y880550D03*
Y865050D03*
X1019999Y845550D03*
X1020499Y828050D03*
X1019999Y917550D03*
X1020499Y900050D03*
X1019999Y971050D03*
X1019499Y951550D03*
X1019999Y934050D03*
Y986550D03*
Y1058550D03*
Y1043050D03*
X1019499Y1023550D03*
X1019999Y1006050D03*
X1020499Y1134050D03*
Y1118550D03*
X1019999Y1099050D03*
X1020499Y1081550D03*
X1019499Y1198550D03*
Y1183050D03*
X1018999Y1163550D03*
X1019499Y1146050D03*
X1016999Y1219050D03*
X1016499Y1301050D03*
Y1236550D03*
X1016999Y1256050D03*
Y1271550D03*
X1023300Y1344400D03*
X1024300Y1365200D03*
X1022599Y1322950D03*
X1024300Y1393600D03*
X1008599Y1716050D03*
X1022299Y1715750D03*
X1008999Y1702450D03*
X1016899Y1731650D03*
X1026899Y1768550D03*
X1020299Y1746650D03*
X1015299Y1765950D03*
X1009999Y1797450D03*
X1022499Y1802050D03*
X1022999Y1784550D03*
X1011299Y1860650D03*
X1007599Y1818450D03*
X1022999Y1821550D03*
Y1837050D03*
X1020499Y1877550D03*
X1020999Y1860050D03*
Y1912550D03*
Y1897050D03*
X1017499Y1954550D03*
X1017999Y1937050D03*
Y1987050D03*
X1023000Y1973000D03*
G54D20*
X279998Y308614D03*
Y304114D03*
Y299614D03*
Y295114D03*
X267498Y310114D03*
Y305114D03*
Y300114D03*
Y295114D03*
X268499Y716550D03*
Y711550D03*
Y701550D03*
Y706550D03*
X280999Y717550D03*
X280433Y713590D03*
X280999Y701550D03*
Y705550D03*
X267349Y1518150D03*
Y1522550D03*
X266999Y1512550D03*
X267349Y1527172D03*
X279499Y1510550D03*
Y1515050D03*
X279075Y1525957D03*
X278567Y1529925D03*
X795526Y1909696D03*
X795493Y1913696D03*
X795501Y1917696D03*
X795499Y1922050D03*
X807997Y1922865D03*
X808005Y1918865D03*
X807936Y1914865D03*
Y1910365D03*
G54D17*
X45800Y405200D03*
X37999Y611550D03*
X80699Y1004450D03*
Y1000450D03*
X34599Y1595300D03*
X80999Y1836550D03*
X82999Y1887550D03*
X78999D03*
Y1891550D03*
X82999D03*
X78999Y1896050D03*
X78433Y1900010D03*
X78999Y1904050D03*
X83499Y1896050D03*
X83433Y1904010D03*
X83999Y1900050D03*
X129999Y78050D03*
X166999Y88050D03*
X166499Y83550D03*
Y79050D03*
X158499D03*
Y84050D03*
Y88550D03*
Y93550D03*
X166999Y92550D03*
Y97050D03*
X127999Y99550D03*
X165499Y106050D03*
X169999Y103050D03*
X173500Y166315D03*
X155999Y181050D03*
X137100Y436800D03*
X129400Y426900D03*
X152000Y520813D03*
X147300Y526700D03*
X147590Y521500D03*
X140940Y561800D03*
X156500Y554000D03*
X152499Y810550D03*
X161999Y768050D03*
X152499Y816050D03*
Y820550D03*
Y825050D03*
X151999Y936550D03*
X152499Y931550D03*
X108200Y963600D03*
X159186Y946117D03*
X151300Y1049300D03*
X105999Y1085800D03*
X101499Y1072550D03*
X100999Y1099550D03*
X105000Y1100500D03*
X100999Y1095050D03*
X105006Y1095366D03*
X125900Y1091282D03*
X132499Y1094550D03*
X106999Y1194550D03*
X102900Y1196050D03*
X103686Y1223863D03*
X103999Y1216863D03*
X119399Y1298113D03*
X175823Y1297070D03*
X175499Y1302113D03*
Y1306113D03*
Y1292550D03*
X116499Y1328013D03*
X120507Y1328096D03*
X135850Y1322250D03*
X106999Y1454450D03*
X100699Y1471050D03*
X98599Y1491350D03*
X105749Y1712749D03*
X117499Y1706050D03*
X128749Y1703300D03*
X133090Y1699959D03*
X131100Y1908500D03*
X129600Y1912400D03*
X124433Y1908510D03*
X124999Y1912550D03*
X98433Y1940510D03*
X98999Y1944550D03*
X102433Y1940555D03*
X103433Y1944510D03*
X187499Y531613D03*
Y536113D03*
X193499Y541113D03*
X188999D03*
X193499Y549613D03*
X188999D03*
Y545613D03*
X193999Y545550D03*
X219499Y939613D03*
Y948613D03*
Y943813D03*
X214999Y939613D03*
Y944113D03*
Y948613D03*
X219499Y926613D03*
X214999D03*
X259999Y1152992D03*
X259499Y1161550D03*
X179999Y1306050D03*
Y1301550D03*
Y1292550D03*
Y1296613D03*
X260999Y1503550D03*
X181100Y1682700D03*
X226999Y1941050D03*
X249600Y1896800D03*
X269500Y1135500D03*
X282500Y1135000D03*
X272499Y1153050D03*
X268499D03*
X263999D03*
X271999Y1161550D03*
X267999D03*
X263499D03*
X334999Y1797050D03*
X326301Y1766030D03*
X306999Y1932550D03*
X302499D03*
X298499D03*
X293999Y1933050D03*
X342999Y1947409D03*
X342621Y1943409D03*
X281999Y1918550D03*
Y1923550D03*
Y1928550D03*
X266999Y1915550D03*
Y1920050D03*
Y1924550D03*
Y1929050D03*
Y1933550D03*
X381499Y65550D03*
X376999D03*
X381499Y70050D03*
X376999D03*
X350499Y597300D03*
X558099Y335050D03*
X557933Y331010D03*
X557999Y322550D03*
Y326550D03*
X558499Y616050D03*
X554304Y615840D03*
X554499Y624550D03*
X558699D03*
X554499Y620050D03*
X558709Y620245D03*
X563499Y1497550D03*
Y1486550D03*
Y1503550D03*
Y1492050D03*
X544300Y1784638D03*
X645549Y1815134D03*
X644360Y1819137D03*
X757999Y154550D03*
Y159050D03*
X753999Y154550D03*
Y159050D03*
X755499Y314550D03*
X751539Y313984D03*
X755346Y319149D03*
X751499Y318050D03*
Y679148D03*
X749499Y716050D03*
X744999Y715550D03*
X749999Y720050D03*
X745499D03*
X757499Y1079550D03*
X755499Y1119050D03*
X749999Y1119550D03*
X748999Y1115550D03*
X748499Y1111550D03*
X757999Y1484050D03*
X751000Y1517000D03*
X757500Y1522500D03*
X751000Y1521000D03*
Y1525000D03*
X751999Y1775550D03*
X756617Y1780067D03*
X752657Y1779496D03*
X755999Y1775550D03*
X756900Y1766000D03*
X753558Y1769946D03*
X757518Y1770517D03*
X752900Y1766000D03*
X732549Y1806634D03*
X733149Y1798634D03*
X707600Y1815600D03*
X733049Y1814134D03*
X758499Y1893550D03*
X837999Y91050D03*
X838999Y85050D03*
X838499Y99550D03*
Y107050D03*
X839499Y119050D03*
X809940Y264940D03*
X808660Y667540D03*
X807000Y1072900D03*
X809960Y1478040D03*
X767159Y1792364D03*
X810900Y1882440D03*
X773999Y1923550D03*
X767999Y1923050D03*
X774499Y1930050D03*
X768999D03*
X802499Y1951550D03*
X800431Y1941193D03*
X843499Y82550D03*
X855499Y82050D03*
X876999D03*
X867499D03*
X845999Y111050D03*
X886499Y99550D03*
Y104550D03*
X890459Y100116D03*
X890499Y104550D03*
X865499Y125550D03*
X875499D03*
X916499Y172550D03*
X903999Y574378D03*
X900999Y979050D03*
X873499Y1356050D03*
X904814Y1789113D03*
X987100Y1624900D03*
X981200Y1625800D03*
X950100Y1626100D03*
G54D16*
X78150Y28858D03*
Y178464D03*
Y434370D03*
Y583976D03*
Y839882D03*
Y989488D03*
Y1245394D03*
Y1395000D03*
Y1650906D03*
Y1800512D03*
X158071Y191614D03*
Y341220D03*
Y597126D03*
Y746732D03*
Y1002638D03*
Y1152244D03*
Y1408150D03*
Y1557756D03*
Y1813662D03*
Y1963268D03*
X886417Y191614D03*
Y341220D03*
Y597126D03*
Y746732D03*
Y1002638D03*
Y1152244D03*
Y1408150D03*
Y1557756D03*
Y1813662D03*
Y1963268D03*
G54D10*
X-39052Y28742D03*
X-43327Y310478D03*
X-39686Y917251D03*
X-38801Y1082342D03*
X-44886Y1294251D03*
X-43103Y1928864D03*
X1071932Y32074D03*
X1074813Y1348051D03*
X1076613Y1740651D03*
X1074813Y1957551D03*
G54D14*
X17720Y1903144D03*
X29532Y309561D03*
Y1029522D03*
X271657Y267711D03*
Y673223D03*
Y1078734D03*
Y1484246D03*
Y1889758D03*
X994098Y149601D03*
Y673223D03*
X994099Y1068892D03*
G54D12*
X9843Y153168D03*
Y265767D03*
Y353144D03*
Y717711D03*
Y762617D03*
Y875216D03*
Y1137420D03*
Y1250019D03*
Y1337396D03*
Y1701963D03*
Y1746869D03*
Y1859468D03*
G54D22*
X1019291Y1416024D03*
Y1694212D03*
G54D18*
X129920Y17716D03*
X994093Y1889751D03*
G54D19*
X172499Y1714050D03*
X167499Y1714113D03*
X162499D03*
X130499Y1730050D03*
X128000Y1735000D03*
X144499Y1729550D03*
X139500Y1730500D03*
X133000Y1734500D03*
X170499Y1731050D03*
X165499Y1730613D03*
X172499Y1726613D03*
X167999D03*
X163499D03*
X227499Y192050D03*
X231999D03*
X227999Y187050D03*
X231999D03*
X227999Y182550D03*
X231999D03*
X227999Y178050D03*
X231999D03*
G54D21*
X809373Y307571D03*
Y297571D03*
Y292571D03*
X808999Y303050D03*
X796873Y307571D03*
Y303071D03*
Y298571D03*
Y294071D03*
X806831Y701853D03*
Y706853D03*
Y711853D03*
X794331Y698353D03*
Y702853D03*
Y707353D03*
Y711853D03*
X806999Y697050D03*
X811499Y1097050D03*
X807499D03*
X807341Y1116216D03*
Y1111216D03*
Y1101216D03*
X806999Y1106050D03*
X802499Y1097566D03*
X798499D03*
X809245Y1518722D03*
Y1508722D03*
Y1503722D03*
X795999Y1518550D03*
Y1514050D03*
Y1509550D03*
Y1504550D03*
X808999Y1513550D03*
%LPC*%
G75*
G54D23*
G01X-71137Y-139897D02*
Y-219897D01*
G01D02*
X1129963D01*
G01X-75137Y-123897D02*
G02I-12000J0D01*
G01X-80287D02*
G02I-6850J0D01*
G01X-87137Y-139897D02*
Y-107897D01*
G01X-71137Y-123897D02*
X-103137D01*
G01X-71137Y-139897D02*
X1129963D01*
G01X-71137Y-175397D02*
X1129963D01*
G01X342463Y-139897D02*
Y-219897D01*
G01X479963Y-139897D02*
Y-219897D01*
G01X594963Y-139897D02*
Y-219897D01*
G01X762463Y-139897D02*
Y-219897D01*
G01X932463Y-139897D02*
Y-219897D01*
G01X1129963Y-139897D02*
Y-219897D01*
G01X1157963Y-123897D02*
G02I-12000J0D01*
G01X1152813D02*
G02I-6850J0D01*
G01X1145963Y-139897D02*
Y-107897D01*
G01X1161963Y-123897D02*
X1129963D01*
G54D24*
G01X-89222Y-207897D02*
Y-190397D01*
G01X-80052D02*
Y-207897D01*
G01Y-199147D02*
X-89222D01*
G01X-67137Y-207897D02*
X-68447Y-207605D01*
X-69757Y-206439D01*
X-70631Y-204397D01*
X-71067Y-202064D01*
X-70631Y-199730D01*
X-69757Y-197689D01*
X-68447Y-196522D01*
X-67137Y-196231D01*
X-65827Y-196522D01*
X-64517Y-197689D01*
X-63644Y-199730D01*
X-63425Y-202064D01*
X-63644Y-204397D01*
X-64517Y-206439D01*
X-65827Y-207605D01*
X-67137Y-207897D01*
G01X-53349D02*
Y-196231D01*
G01Y-199147D02*
X-52475Y-197689D01*
X-51165Y-196522D01*
X-49419Y-196231D01*
X-47891Y-196522D01*
X-46580Y-197689D01*
X-45925Y-199730D01*
Y-207897D01*
G01X-35412Y-200022D02*
X-28425D01*
X-29080Y-197980D01*
X-30172Y-196814D01*
X-31700Y-196231D01*
X-33229Y-196522D01*
X-34539Y-197397D01*
X-35412Y-199439D01*
X-35849Y-201189D01*
Y-202939D01*
X-35412Y-204689D01*
X-34320Y-206439D01*
X-33010Y-207605D01*
X-31482Y-207897D01*
X-29954Y-207314D01*
X-28425Y-205564D01*
G01X-19222Y-213147D02*
X-17912Y-213730D01*
X-16165Y-213147D01*
X-15074Y-211981D01*
X-14200Y-210522D01*
X-12891Y-205856D01*
X-10052Y-196231D01*
G01X-17039D02*
X-12891Y-205856D01*
G01X22109Y-198564D02*
X22983Y-197689D01*
X23638Y-196231D01*
X24075Y-194188D01*
X23638Y-192439D01*
X22765Y-191272D01*
X21236Y-190397D01*
X15341D01*
Y-207897D01*
X22546D01*
X24075Y-206731D01*
X24948Y-204980D01*
X25385Y-202939D01*
X24948Y-200897D01*
X23638Y-199147D01*
X22109Y-198564D01*
X15341D01*
G01X41793Y-207897D02*
Y-196231D01*
G01Y-198272D02*
X40920Y-197106D01*
X39609Y-196522D01*
X38081Y-196231D01*
X36553Y-196814D01*
X35243Y-197980D01*
X34369Y-199730D01*
X33933Y-202064D01*
X34369Y-204397D01*
X35243Y-206147D01*
X36553Y-207314D01*
X38081Y-207897D01*
X39609Y-207605D01*
X40920Y-206731D01*
X41793Y-205564D01*
G01X59293Y-190397D02*
Y-207897D01*
G01Y-205273D02*
X58420Y-206731D01*
X57109Y-207605D01*
X55581Y-207897D01*
X53835Y-207314D01*
X52525Y-205856D01*
X51651Y-204106D01*
X51433Y-202064D01*
X51651Y-200022D01*
X52525Y-198272D01*
X53835Y-196814D01*
X55581Y-196231D01*
X57109Y-196522D01*
X58201Y-197106D01*
X59293Y-198272D01*
G01X69806Y-212272D02*
X71335Y-213439D01*
X73081Y-213730D01*
X74609Y-213439D01*
X75920Y-211981D01*
X76793Y-209939D01*
Y-196231D01*
G01Y-198564D02*
X75920Y-197397D01*
X74609Y-196522D01*
X73081Y-196231D01*
X71335Y-196814D01*
X70243Y-197980D01*
X69369Y-200022D01*
X68933Y-202064D01*
X69151Y-203814D01*
X70025Y-205856D01*
X71335Y-207314D01*
X73081Y-207897D01*
X74391Y-207605D01*
X75920Y-206439D01*
X76793Y-205273D01*
G01X87088Y-200022D02*
X94075D01*
X93420Y-197980D01*
X92328Y-196814D01*
X90800Y-196231D01*
X89271Y-196522D01*
X87961Y-197397D01*
X87088Y-199439D01*
X86651Y-201189D01*
Y-202939D01*
X87088Y-204689D01*
X88180Y-206439D01*
X89490Y-207605D01*
X91018Y-207897D01*
X92546Y-207314D01*
X94075Y-205564D01*
G01X104806Y-207897D02*
Y-196231D01*
G01Y-198564D02*
X105898Y-197397D01*
X106990Y-196522D01*
X108518Y-196231D01*
X109609Y-196522D01*
X110920Y-197397D01*
G01X138060Y-207897D02*
Y-190397D01*
X142426D01*
X144173Y-191272D01*
X145483Y-192439D01*
X146575Y-194188D01*
X147448Y-196231D01*
X147666Y-199147D01*
X147448Y-202064D01*
X146575Y-204106D01*
X145483Y-205856D01*
X144173Y-207022D01*
X142426Y-207897D01*
X138060D01*
G01X155996D02*
Y-190397D01*
X161236D01*
X162983Y-191272D01*
X164293Y-193314D01*
X164730Y-195647D01*
X164293Y-197980D01*
X163201Y-199730D01*
X161236Y-200606D01*
X155996D01*
G01X179609Y-198564D02*
X180483Y-197689D01*
X181138Y-196231D01*
X181575Y-194188D01*
X181138Y-192439D01*
X180265Y-191272D01*
X178736Y-190397D01*
X172841D01*
Y-207897D01*
X180046D01*
X181575Y-206731D01*
X182448Y-204980D01*
X182885Y-202939D01*
X182448Y-200897D01*
X181138Y-199147D01*
X179609Y-198564D01*
X172841D01*
G01X208496Y-190397D02*
Y-207897D01*
X217230D01*
G01X230363D02*
X229053Y-207605D01*
X227743Y-206439D01*
X226869Y-204397D01*
X226433Y-202064D01*
X226869Y-199730D01*
X227743Y-197689D01*
X229053Y-196522D01*
X230363Y-196231D01*
X231673Y-196522D01*
X232983Y-197689D01*
X233856Y-199730D01*
X234075Y-202064D01*
X233856Y-204397D01*
X232983Y-206439D01*
X231673Y-207605D01*
X230363Y-207897D01*
G01X242404Y-196231D02*
X245025Y-207897D01*
X247863Y-196231D01*
X250701Y-207897D01*
X253322Y-196231D01*
G01X278496Y-190397D02*
Y-207897D01*
X287230D01*
G01X300363D02*
X299053Y-207605D01*
X297743Y-206439D01*
X296869Y-204397D01*
X296433Y-202064D01*
X296869Y-199730D01*
X297743Y-197689D01*
X299053Y-196522D01*
X300363Y-196231D01*
X301673Y-196522D01*
X302983Y-197689D01*
X303856Y-199730D01*
X304075Y-202064D01*
X303856Y-204397D01*
X302983Y-206439D01*
X301673Y-207605D01*
X300363Y-207897D01*
G01X314588Y-205856D02*
X315680Y-207022D01*
X317208Y-207897D01*
X318518D01*
X319828Y-207314D01*
X320701Y-206439D01*
X321138Y-205273D01*
X320920Y-203522D01*
X320046Y-202647D01*
X316116Y-200897D01*
X315243Y-198855D01*
X315680Y-197397D01*
X316553Y-196522D01*
X317863Y-196231D01*
X319173Y-196522D01*
X320483Y-197397D01*
G01X332088Y-205856D02*
X333180Y-207022D01*
X334708Y-207897D01*
X336018D01*
X337328Y-207314D01*
X338201Y-206439D01*
X338638Y-205273D01*
X338420Y-203522D01*
X337546Y-202647D01*
X333616Y-200897D01*
X332743Y-198855D01*
X333180Y-197397D01*
X334053Y-196522D01*
X335363Y-196231D01*
X336673Y-196522D01*
X337983Y-197397D01*
G01X94686Y-164897D02*
Y-147397D01*
X100363Y-161980D01*
X106040Y-147397D01*
Y-164897D01*
G01X117863D02*
X116553Y-164605D01*
X115243Y-163439D01*
X114369Y-161397D01*
X113933Y-159064D01*
X114369Y-156730D01*
X115243Y-154689D01*
X116553Y-153522D01*
X117863Y-153231D01*
X119173Y-153522D01*
X120483Y-154689D01*
X121356Y-156730D01*
X121575Y-159064D01*
X121356Y-161397D01*
X120483Y-163439D01*
X119173Y-164605D01*
X117863Y-164897D01*
G01X139293Y-147397D02*
Y-164897D01*
G01Y-162273D02*
X138420Y-163731D01*
X137109Y-164605D01*
X135581Y-164897D01*
X133835Y-164314D01*
X132525Y-162856D01*
X131651Y-161106D01*
X131433Y-159064D01*
X131651Y-157022D01*
X132525Y-155272D01*
X133835Y-153814D01*
X135581Y-153231D01*
X137109Y-153522D01*
X138201Y-154106D01*
X139293Y-155272D01*
G01X149588Y-157022D02*
X156575D01*
X155920Y-154980D01*
X154828Y-153814D01*
X153300Y-153231D01*
X151771Y-153522D01*
X150461Y-154397D01*
X149588Y-156439D01*
X149151Y-158189D01*
Y-159939D01*
X149588Y-161689D01*
X150680Y-163439D01*
X151990Y-164605D01*
X153518Y-164897D01*
X155046Y-164314D01*
X156575Y-162564D01*
G01X170363Y-164897D02*
Y-147397D01*
G01X376163Y-209897D02*
Y-192397D01*
X373543Y-195897D01*
G01Y-209897D02*
X378783D01*
G01X396283D02*
Y-192397D01*
X388204Y-204939D01*
X399122D01*
G01X406360Y-207273D02*
X407669Y-208731D01*
X409198Y-209605D01*
X411163Y-209897D01*
X413128Y-209314D01*
X414656Y-208147D01*
X415748Y-206106D01*
X415966Y-203772D01*
X415530Y-201439D01*
X414438Y-199980D01*
X412909Y-198814D01*
X411381Y-198522D01*
X409853Y-198814D01*
X407888Y-199980D01*
X408543Y-192397D01*
X414438D01*
G01X431283Y-209897D02*
Y-192397D01*
X423204Y-204939D01*
X434122D01*
G01X441360Y-207273D02*
X442669Y-208731D01*
X444198Y-209605D01*
X446163Y-209897D01*
X448128Y-209314D01*
X449656Y-208147D01*
X450748Y-206106D01*
X450966Y-203772D01*
X450530Y-201439D01*
X449438Y-199980D01*
X447909Y-198814D01*
X446381Y-198522D01*
X444853Y-198814D01*
X442888Y-199980D01*
X443543Y-192397D01*
X449438D01*
G01X363046Y-164897D02*
Y-147397D01*
X368286D01*
X370033Y-148272D01*
X371343Y-150314D01*
X371780Y-152647D01*
X371343Y-154980D01*
X370251Y-156730D01*
X368286Y-157606D01*
X363046D01*
G01X389716Y-148856D02*
X388406Y-147980D01*
X386878Y-147397D01*
X385131D01*
X383166Y-148272D01*
X381638Y-149730D01*
X380546Y-151481D01*
X379673Y-154397D01*
X379454Y-157022D01*
X379891Y-159647D01*
X380546Y-161397D01*
X381856Y-163147D01*
X383385Y-164314D01*
X384913Y-164897D01*
X386441D01*
X387970Y-164314D01*
X389280Y-163439D01*
X390372Y-162273D01*
G01X404159Y-155564D02*
X405033Y-154689D01*
X405688Y-153231D01*
X406125Y-151188D01*
X405688Y-149439D01*
X404815Y-148272D01*
X403286Y-147397D01*
X397391D01*
Y-164897D01*
X404596D01*
X406125Y-163731D01*
X406998Y-161980D01*
X407435Y-159939D01*
X406998Y-157897D01*
X405688Y-156147D01*
X404159Y-155564D01*
X397391D01*
G01X413363Y-170730D02*
X426463D01*
G01X432391Y-164897D02*
Y-147397D01*
X442435Y-164897D01*
Y-147397D01*
G01X454913Y-164897D02*
X453166Y-164605D01*
X451638Y-163439D01*
X450328Y-161689D01*
X449454Y-159647D01*
X449018Y-157314D01*
Y-154980D01*
X449454Y-152647D01*
X450328Y-150605D01*
X451638Y-148856D01*
X453166Y-147689D01*
X454913Y-147397D01*
X456659Y-147689D01*
X458188Y-148856D01*
X459498Y-150605D01*
X460372Y-152647D01*
X460808Y-154980D01*
Y-157314D01*
X460372Y-159647D01*
X459498Y-161689D01*
X458188Y-163439D01*
X456659Y-164605D01*
X454913Y-164897D01*
G01X505754Y-147397D02*
X511213Y-164897D01*
X516672Y-147397D01*
G01X533080Y-164897D02*
X524346D01*
Y-147397D01*
X533080D01*
G01X529586Y-155855D02*
X524346D01*
G01X541846Y-164897D02*
Y-147397D01*
X547305D01*
X549051Y-148272D01*
X550143Y-149439D01*
X550580Y-151772D01*
X550143Y-154106D01*
X548833Y-155564D01*
X547305Y-156439D01*
X541846D01*
G01X547305D02*
X550580Y-164897D01*
G01X563713Y-165480D02*
X563276Y-165189D01*
Y-164605D01*
X563713Y-164314D01*
X564150Y-164605D01*
Y-165189D01*
X563713Y-165480D01*
G01X524128Y-207564D02*
X525875Y-209022D01*
X527840Y-209897D01*
X529586D01*
X531333Y-209022D01*
X532643Y-207564D01*
X533298Y-205522D01*
X532861Y-203481D01*
X531770Y-201730D01*
X529805Y-200564D01*
X527185Y-199980D01*
X525656Y-198814D01*
X525001Y-196772D01*
X525438Y-194730D01*
X526530Y-193272D01*
X528058Y-192397D01*
X529586D01*
X531115Y-192980D01*
X532425Y-194439D01*
G01X540754Y-209897D02*
X546213Y-192397D01*
X551672Y-209897D01*
G01X549706Y-203772D02*
X542719D01*
G01X639296Y-192397D02*
Y-209897D01*
X648030D01*
G01X663783D02*
Y-192397D01*
X655704Y-204939D01*
X666622D01*
G01X673204Y-192397D02*
X678663Y-209897D01*
X684122Y-192397D01*
G01X700966Y-193856D02*
X699656Y-192980D01*
X698128Y-192397D01*
X696381D01*
X694416Y-193272D01*
X692888Y-194730D01*
X691796Y-196481D01*
X690923Y-199397D01*
X690704Y-202022D01*
X691141Y-204647D01*
X691796Y-206397D01*
X693106Y-208147D01*
X694635Y-209314D01*
X696163Y-209897D01*
X697691D01*
X699220Y-209314D01*
X700530Y-208439D01*
X701622Y-207273D01*
G01X718466Y-193856D02*
X717156Y-192980D01*
X715628Y-192397D01*
X713881D01*
X711916Y-193272D01*
X710388Y-194730D01*
X709296Y-196481D01*
X708423Y-199397D01*
X708204Y-202022D01*
X708641Y-204647D01*
X709296Y-206397D01*
X710606Y-208147D01*
X712135Y-209314D01*
X713663Y-209897D01*
X715191D01*
X716720Y-209314D01*
X718030Y-208439D01*
X719122Y-207273D01*
G01X630546Y-147397D02*
Y-164897D01*
X639280D01*
G01X656343D02*
Y-153231D01*
G01Y-155272D02*
X655470Y-154106D01*
X654159Y-153522D01*
X652631Y-153231D01*
X651103Y-153814D01*
X649793Y-154980D01*
X648919Y-156730D01*
X648483Y-159064D01*
X648919Y-161397D01*
X649793Y-163147D01*
X651103Y-164314D01*
X652631Y-164897D01*
X654159Y-164605D01*
X655470Y-163731D01*
X656343Y-162564D01*
G01X665328Y-170147D02*
X666638Y-170730D01*
X668385Y-170147D01*
X669476Y-168981D01*
X670350Y-167522D01*
X671659Y-162856D01*
X674498Y-153231D01*
G01X667511D02*
X671659Y-162856D01*
G01X684138Y-157022D02*
X691125D01*
X690470Y-154980D01*
X689378Y-153814D01*
X687850Y-153231D01*
X686321Y-153522D01*
X685011Y-154397D01*
X684138Y-156439D01*
X683701Y-158189D01*
Y-159939D01*
X684138Y-161689D01*
X685230Y-163439D01*
X686540Y-164605D01*
X688068Y-164897D01*
X689596Y-164314D01*
X691125Y-162564D01*
G01X701856Y-164897D02*
Y-153231D01*
G01Y-155564D02*
X702948Y-154397D01*
X704040Y-153522D01*
X705568Y-153231D01*
X706659Y-153522D01*
X707970Y-154397D01*
G01X719138Y-162856D02*
X720230Y-164022D01*
X721758Y-164897D01*
X723068D01*
X724378Y-164314D01*
X725251Y-163439D01*
X725688Y-162273D01*
X725470Y-160522D01*
X724596Y-159647D01*
X720666Y-157897D01*
X719793Y-155855D01*
X720230Y-154397D01*
X721103Y-153522D01*
X722413Y-153231D01*
X723723Y-153522D01*
X725033Y-154397D01*
G01X790596Y-209897D02*
Y-192397D01*
X796055D01*
X797801Y-193272D01*
X798893Y-194439D01*
X799330Y-196772D01*
X798893Y-199106D01*
X797583Y-200564D01*
X796055Y-201439D01*
X790596D01*
G01X796055D02*
X799330Y-209897D01*
G01X809188Y-202022D02*
X816175D01*
X815520Y-199980D01*
X814428Y-198814D01*
X812900Y-198231D01*
X811371Y-198522D01*
X810061Y-199397D01*
X809188Y-201439D01*
X808751Y-203189D01*
Y-204939D01*
X809188Y-206689D01*
X810280Y-208439D01*
X811590Y-209605D01*
X813118Y-209897D01*
X814646Y-209314D01*
X816175Y-207564D01*
G01X826033Y-209897D02*
Y-192397D01*
G01Y-201147D02*
X827125Y-199397D01*
X828435Y-198522D01*
X829745Y-198231D01*
X831709Y-198814D01*
X833020Y-199980D01*
X833893Y-202022D01*
Y-204355D01*
X833456Y-206689D01*
X832583Y-208439D01*
X831055Y-209605D01*
X829745Y-209897D01*
X828435Y-209605D01*
X827125Y-208731D01*
X826033Y-207273D01*
G01X844188Y-202022D02*
X851175D01*
X850520Y-199980D01*
X849428Y-198814D01*
X847900Y-198231D01*
X846371Y-198522D01*
X845061Y-199397D01*
X844188Y-201439D01*
X843751Y-203189D01*
Y-204939D01*
X844188Y-206689D01*
X845280Y-208439D01*
X846590Y-209605D01*
X848118Y-209897D01*
X849646Y-209314D01*
X851175Y-207564D01*
G01X868456Y-199689D02*
X866928Y-198522D01*
X865618Y-198231D01*
X863871Y-198814D01*
X862561Y-199980D01*
X861688Y-202022D01*
X861469Y-204064D01*
X861688Y-206106D01*
X862561Y-207856D01*
X863871Y-209314D01*
X865618Y-209897D01*
X867146Y-209314D01*
X868456Y-208147D01*
G01X885956Y-199689D02*
X884428Y-198522D01*
X883118Y-198231D01*
X881371Y-198814D01*
X880061Y-199980D01*
X879188Y-202022D01*
X878969Y-204064D01*
X879188Y-206106D01*
X880061Y-207856D01*
X881371Y-209314D01*
X883118Y-209897D01*
X884646Y-209314D01*
X885956Y-208147D01*
G01X903893Y-209897D02*
Y-198231D01*
G01Y-200272D02*
X903020Y-199106D01*
X901709Y-198522D01*
X900181Y-198231D01*
X898653Y-198814D01*
X897343Y-199980D01*
X896469Y-201730D01*
X896033Y-204064D01*
X896469Y-206397D01*
X897343Y-208147D01*
X898653Y-209314D01*
X900181Y-209897D01*
X901709Y-209605D01*
X903020Y-208731D01*
X903893Y-207564D01*
G01X781410Y-164897D02*
Y-147397D01*
X785776D01*
X787523Y-148272D01*
X788833Y-149439D01*
X789925Y-151188D01*
X790798Y-153231D01*
X791016Y-156147D01*
X790798Y-159064D01*
X789925Y-161106D01*
X788833Y-162856D01*
X787523Y-164022D01*
X785776Y-164897D01*
X781410D01*
G01X800438Y-157022D02*
X807425D01*
X806770Y-154980D01*
X805678Y-153814D01*
X804150Y-153231D01*
X802621Y-153522D01*
X801311Y-154397D01*
X800438Y-156439D01*
X800001Y-158189D01*
Y-159939D01*
X800438Y-161689D01*
X801530Y-163439D01*
X802840Y-164605D01*
X804368Y-164897D01*
X805896Y-164314D01*
X807425Y-162564D01*
G01X817938Y-162856D02*
X819030Y-164022D01*
X820558Y-164897D01*
X821868D01*
X823178Y-164314D01*
X824051Y-163439D01*
X824488Y-162273D01*
X824270Y-160522D01*
X823396Y-159647D01*
X819466Y-157897D01*
X818593Y-155855D01*
X819030Y-154397D01*
X819903Y-153522D01*
X821213Y-153231D01*
X822523Y-153522D01*
X823833Y-154397D01*
G01X838713Y-153231D02*
Y-164897D01*
G01Y-148564D02*
X838276Y-148272D01*
Y-147689D01*
X838713Y-147397D01*
X839150Y-147689D01*
Y-148272D01*
X838713Y-148564D01*
G01X853156Y-169272D02*
X854685Y-170439D01*
X856431Y-170730D01*
X857959Y-170439D01*
X859270Y-168981D01*
X860143Y-166939D01*
Y-153231D01*
G01Y-155564D02*
X859270Y-154397D01*
X857959Y-153522D01*
X856431Y-153231D01*
X854685Y-153814D01*
X853593Y-154980D01*
X852719Y-157022D01*
X852283Y-159064D01*
X852501Y-160814D01*
X853375Y-162856D01*
X854685Y-164314D01*
X856431Y-164897D01*
X857741Y-164605D01*
X859270Y-163439D01*
X860143Y-162273D01*
G01X870001Y-164897D02*
Y-153231D01*
G01Y-156147D02*
X870875Y-154689D01*
X872185Y-153522D01*
X873931Y-153231D01*
X875459Y-153522D01*
X876770Y-154689D01*
X877425Y-156730D01*
Y-164897D01*
G01X887938Y-157022D02*
X894925D01*
X894270Y-154980D01*
X893178Y-153814D01*
X891650Y-153231D01*
X890121Y-153522D01*
X888811Y-154397D01*
X887938Y-156439D01*
X887501Y-158189D01*
Y-159939D01*
X887938Y-161689D01*
X889030Y-163439D01*
X890340Y-164605D01*
X891868Y-164897D01*
X893396Y-164314D01*
X894925Y-162564D01*
G01X905656Y-164897D02*
Y-153231D01*
G01Y-155564D02*
X906748Y-154397D01*
X907840Y-153522D01*
X909368Y-153231D01*
X910459Y-153522D01*
X911770Y-154397D01*
G01X952413Y-192397D02*
X950666Y-192980D01*
X949356Y-194439D01*
X948483Y-196188D01*
X947828Y-198522D01*
X947610Y-201147D01*
X947828Y-203772D01*
X948483Y-206106D01*
X949356Y-207856D01*
X950666Y-209314D01*
X952413Y-209897D01*
X954159Y-209314D01*
X955470Y-207856D01*
X956343Y-206106D01*
X956998Y-203772D01*
X957216Y-201147D01*
X956998Y-198522D01*
X956343Y-196188D01*
X955470Y-194439D01*
X954159Y-192980D01*
X952413Y-192397D01*
G01X969913Y-209897D02*
X971441Y-209605D01*
X973188Y-208731D01*
X974280Y-207273D01*
X974716Y-205230D01*
X974280Y-203189D01*
X972970Y-201439D01*
X971005Y-200564D01*
X968821D01*
X967511Y-199980D01*
X966419Y-198522D01*
X965983Y-196481D01*
X966638Y-194439D01*
X968166Y-192980D01*
X969913Y-192397D01*
X971659Y-192980D01*
X973188Y-194439D01*
X973843Y-196481D01*
X973406Y-198522D01*
X972315Y-199980D01*
X971005Y-200564D01*
X968821D01*
X966856Y-201439D01*
X965546Y-203189D01*
X965110Y-205230D01*
X965546Y-207273D01*
X966638Y-208731D01*
X968385Y-209605D01*
X969913Y-209897D01*
G01X983483Y-210480D02*
X991343Y-192397D01*
G01X1004913D02*
X1003166Y-192980D01*
X1001856Y-194439D01*
X1000983Y-196188D01*
X1000328Y-198522D01*
X1000110Y-201147D01*
X1000328Y-203772D01*
X1000983Y-206106D01*
X1001856Y-207856D01*
X1003166Y-209314D01*
X1004913Y-209897D01*
X1006659Y-209314D01*
X1007970Y-207856D01*
X1008843Y-206106D01*
X1009498Y-203772D01*
X1009716Y-201147D01*
X1009498Y-198522D01*
X1008843Y-196188D01*
X1007970Y-194439D01*
X1006659Y-192980D01*
X1004913Y-192397D01*
G01X1022413Y-209897D02*
Y-192397D01*
X1019793Y-195897D01*
G01Y-209897D02*
X1025033D01*
G01X1035983Y-210480D02*
X1043843Y-192397D01*
G01X1053265Y-195314D02*
X1054575Y-193564D01*
X1056103Y-192689D01*
X1057850Y-192397D01*
X1060033Y-192980D01*
X1061561Y-194439D01*
X1061998Y-196188D01*
X1061780Y-197939D01*
X1060906Y-199397D01*
X1056540Y-202314D01*
X1054575Y-204355D01*
X1053265Y-207273D01*
X1052828Y-209897D01*
X1061998D01*
G01X1074913Y-192397D02*
X1073166Y-192980D01*
X1071856Y-194439D01*
X1070983Y-196188D01*
X1070328Y-198522D01*
X1070110Y-201147D01*
X1070328Y-203772D01*
X1070983Y-206106D01*
X1071856Y-207856D01*
X1073166Y-209314D01*
X1074913Y-209897D01*
X1076659Y-209314D01*
X1077970Y-207856D01*
X1078843Y-206106D01*
X1079498Y-203772D01*
X1079716Y-201147D01*
X1079498Y-198522D01*
X1078843Y-196188D01*
X1077970Y-194439D01*
X1076659Y-192980D01*
X1074913Y-192397D01*
G01X1092413Y-209897D02*
Y-192397D01*
X1089793Y-195897D01*
G01Y-209897D02*
X1095033D01*
G01X1112533D02*
Y-192397D01*
X1104454Y-204939D01*
X1115372D01*
G01X1000110Y-164897D02*
Y-147397D01*
X1004476D01*
X1006223Y-148272D01*
X1007533Y-149439D01*
X1008625Y-151188D01*
X1009498Y-153231D01*
X1009716Y-156147D01*
X1009498Y-159064D01*
X1008625Y-161106D01*
X1007533Y-162856D01*
X1006223Y-164022D01*
X1004476Y-164897D01*
X1000110D01*
G01X1026343D02*
Y-153231D01*
G01Y-155272D02*
X1025470Y-154106D01*
X1024159Y-153522D01*
X1022631Y-153231D01*
X1021103Y-153814D01*
X1019793Y-154980D01*
X1018919Y-156730D01*
X1018483Y-159064D01*
X1018919Y-161397D01*
X1019793Y-163147D01*
X1021103Y-164314D01*
X1022631Y-164897D01*
X1024159Y-164605D01*
X1025470Y-163731D01*
X1026343Y-162564D01*
G01X1039913Y-147397D02*
Y-164897D01*
G01X1036856Y-153231D02*
X1042970D01*
G01X1054138Y-157022D02*
X1061125D01*
X1060470Y-154980D01*
X1059378Y-153814D01*
X1057850Y-153231D01*
X1056321Y-153522D01*
X1055011Y-154397D01*
X1054138Y-156439D01*
X1053701Y-158189D01*
Y-159939D01*
X1054138Y-161689D01*
X1055230Y-163439D01*
X1056540Y-164605D01*
X1058068Y-164897D01*
X1059596Y-164314D01*
X1061125Y-162564D01*
M02*
